FILE_TYPE = MACRO_DRAWING;
SET COLOR_WIRE YELLOW;
SET COLOR_PROP ORANGE;
SET COLOR_DOT WHITE;
SET COLOR_ARC YELLOW;
SET COLOR_BODY GREEN;
SET COLOR_NOTE PURPLE;
SET PROP_DISPLAY VALUE;
SET PAGE_NUMBER P100;
FORCEADD OFFPAGE..5
(-8400 2125);
FORCEPROP 2 LAST $XR0 40 
J 0
(-8654 2125);
DISPLAY 0.638298 (-8654 2125);
PAINT MONO (-8654 2125);
FORCEPROP 2 LAST CDS_LIB mstr_standard
J 0
(-8400 2125);
DISPLAY 0.808511 (-8400 2125);
DISPLAY INVISIBLE (-8400 2125);
FORCEPROP 1 LAST OFFPAGE TRUE
J 0
(-8075 2000);
DISPLAY 0.872340 (-8075 2000);
PAINT GREEN (-8075 2000);
DISPLAY INVISIBLE (-8075 2000);
FORCEPROP 1 LAST COMMENT_BODY TRUE
J 0
(-8300 2050);
DISPLAY 0.872340 (-8300 2050);
PAINT GREEN (-8300 2050);
DISPLAY INVISIBLE (-8300 2050);
FORCEPROP 2 LAST PATH I1
J 0
(-8600 2175);
DISPLAY 1.021277 (-8600 2175);
DISPLAY INVISIBLE (-8600 2175);
FORCEADD OFFPAGE..6
(-8400 3775);
FORCEPROP 2 LAST $XR0 40 
J 0
(-8649 3775);
DISPLAY 0.638298 (-8649 3775);
PAINT MONO (-8649 3775);
FORCEPROP 2 LAST CDS_LIB mstr_standard
J 0
(-8400 3775);
DISPLAY 0.723404 (-8400 3775);
PAINT MONO (-8400 3775);
DISPLAY INVISIBLE (-8400 3775);
FORCEPROP 1 LAST OFFPAGE TRUE
J 0
(-8075 3650);
DISPLAY 0.872340 (-8075 3650);
PAINT GREEN (-8075 3650);
DISPLAY INVISIBLE (-8075 3650);
FORCEPROP 1 LAST COMMENT_BODY TRUE
J 0
(-8300 3700);
DISPLAY 0.872340 (-8300 3700);
PAINT GREEN (-8300 3700);
DISPLAY INVISIBLE (-8300 3700);
FORCEPROP 2 LAST PATH I10
J 0
(-8625 3825);
DISPLAY 1.021277 (-8625 3825);
DISPLAY INVISIBLE (-8625 3825);
FORCEADD TAP..1
(-6100 4225);
FORCEPROP 3 LASTPIN (-6150 4225) SIG_NAME M_D_CPU1_SA_DQ<4>
J 0
(-6140 4235);
DISPLAY 0.659574 (-6140 4235);
PAINT MONO (-6140 4235);
DISPLAY INVISIBLE (-6140 4235);
FORCEPROP 1 LASTPIN (-6150 4225) BN 4
J 0
(-6162 4233);
DISPLAY 0.489362 (-6162 4233);
PAINT GREEN (-6162 4233);
FORCEPROP 2 LAST CDS_LIB mstr_standard
J 0
(-6100 4225);
DISPLAY 0.723404 (-6100 4225);
PAINT MONO (-6100 4225);
DISPLAY INVISIBLE (-6100 4225);
FORCEPROP 1 LAST BODY_TYPE PLUMBING
J 0
(-6100 4275);
DISPLAY 0.872340 (-6100 4275);
PAINT GREEN (-6100 4275);
DISPLAY INVISIBLE (-6100 4275);
FORCEPROP 1 LAST HDL_TAP TRUE
J 0
(-5775 4100);
DISPLAY 0.872340 (-5775 4100);
DISPLAY INVISIBLE (-5775 4100);
FORCEPROP 1 LAST PATH I107
J 0
(-6102 4225);
DISPLAY 0.872340 (-6102 4225);
PAINT GREEN (-6102 4225);
DISPLAY INVISIBLE (-6102 4225);
FORCEADD TAP..1
(-6100 4275);
FORCEPROP 3 LASTPIN (-6150 4275) SIG_NAME M_D_CPU1_SA_DQ<5>
J 0
(-6140 4285);
DISPLAY 0.659574 (-6140 4285);
PAINT MONO (-6140 4285);
DISPLAY INVISIBLE (-6140 4285);
FORCEPROP 1 LASTPIN (-6150 4275) BN 5
J 0
(-6162 4283);
DISPLAY 0.489362 (-6162 4283);
PAINT GREEN (-6162 4283);
FORCEPROP 2 LAST CDS_LIB mstr_standard
J 0
(-6100 4275);
DISPLAY 0.723404 (-6100 4275);
PAINT MONO (-6100 4275);
DISPLAY INVISIBLE (-6100 4275);
FORCEPROP 1 LAST BODY_TYPE PLUMBING
J 0
(-6100 4325);
DISPLAY 0.872340 (-6100 4325);
PAINT GREEN (-6100 4325);
DISPLAY INVISIBLE (-6100 4325);
FORCEPROP 1 LAST HDL_TAP TRUE
J 0
(-5775 4150);
DISPLAY 0.872340 (-5775 4150);
DISPLAY INVISIBLE (-5775 4150);
FORCEPROP 1 LAST PATH I108
J 0
(-6102 4275);
DISPLAY 0.872340 (-6102 4275);
PAINT GREEN (-6102 4275);
DISPLAY INVISIBLE (-6102 4275);
FORCEADD TAP..1
(-6100 4325);
FORCEPROP 3 LASTPIN (-6150 4325) SIG_NAME M_D_CPU1_SA_DQ<6>
J 0
(-6140 4335);
DISPLAY 0.659574 (-6140 4335);
PAINT MONO (-6140 4335);
DISPLAY INVISIBLE (-6140 4335);
FORCEPROP 1 LASTPIN (-6150 4325) BN 6
J 0
(-6162 4333);
DISPLAY 0.489362 (-6162 4333);
PAINT GREEN (-6162 4333);
FORCEPROP 2 LAST CDS_LIB mstr_standard
J 0
(-6100 4325);
DISPLAY 0.723404 (-6100 4325);
PAINT MONO (-6100 4325);
DISPLAY INVISIBLE (-6100 4325);
FORCEPROP 1 LAST BODY_TYPE PLUMBING
J 0
(-6100 4375);
DISPLAY 0.872340 (-6100 4375);
PAINT GREEN (-6100 4375);
DISPLAY INVISIBLE (-6100 4375);
FORCEPROP 1 LAST HDL_TAP TRUE
J 0
(-5775 4200);
DISPLAY 0.872340 (-5775 4200);
DISPLAY INVISIBLE (-5775 4200);
FORCEPROP 1 LAST PATH I109
J 0
(-6102 4325);
DISPLAY 0.872340 (-6102 4325);
PAINT GREEN (-6102 4325);
DISPLAY INVISIBLE (-6102 4325);
FORCEADD OFFPAGE..6
(-8400 4225);
FORCEPROP 2 LAST $XR0 40 
J 0
(-8649 4225);
DISPLAY 0.638298 (-8649 4225);
PAINT MONO (-8649 4225);
FORCEPROP 2 LAST CDS_LIB mstr_standard
J 0
(-8400 4225);
DISPLAY 0.723404 (-8400 4225);
PAINT MONO (-8400 4225);
DISPLAY INVISIBLE (-8400 4225);
FORCEPROP 1 LAST OFFPAGE TRUE
J 0
(-8075 4100);
DISPLAY 0.872340 (-8075 4100);
PAINT GREEN (-8075 4100);
DISPLAY INVISIBLE (-8075 4100);
FORCEPROP 1 LAST COMMENT_BODY TRUE
J 0
(-8300 4150);
DISPLAY 0.872340 (-8300 4150);
PAINT GREEN (-8300 4150);
DISPLAY INVISIBLE (-8300 4150);
FORCEPROP 2 LAST PATH I11
J 0
(-8625 4275);
DISPLAY 1.021277 (-8625 4275);
DISPLAY INVISIBLE (-8625 4275);
FORCEADD TAP..1
(-6100 4375);
FORCEPROP 3 LASTPIN (-6150 4375) SIG_NAME M_D_CPU1_SA_DQ<7>
J 0
(-6140 4385);
DISPLAY 0.659574 (-6140 4385);
PAINT MONO (-6140 4385);
DISPLAY INVISIBLE (-6140 4385);
FORCEPROP 1 LASTPIN (-6150 4375) BN 7
J 0
(-6162 4383);
DISPLAY 0.489362 (-6162 4383);
PAINT GREEN (-6162 4383);
FORCEPROP 2 LAST CDS_LIB mstr_standard
J 0
(-6100 4375);
DISPLAY 0.723404 (-6100 4375);
PAINT MONO (-6100 4375);
DISPLAY INVISIBLE (-6100 4375);
FORCEPROP 1 LAST BODY_TYPE PLUMBING
J 0
(-6100 4425);
DISPLAY 0.872340 (-6100 4425);
PAINT GREEN (-6100 4425);
DISPLAY INVISIBLE (-6100 4425);
FORCEPROP 1 LAST HDL_TAP TRUE
J 0
(-5775 4250);
DISPLAY 0.872340 (-5775 4250);
DISPLAY INVISIBLE (-5775 4250);
FORCEPROP 1 LAST PATH I110
J 0
(-6102 4375);
DISPLAY 0.872340 (-6102 4375);
PAINT GREEN (-6102 4375);
DISPLAY INVISIBLE (-6102 4375);
FORCEADD TAP..1
(-6100 4425);
FORCEPROP 3 LASTPIN (-6150 4425) SIG_NAME M_D_CPU1_SA_DQ<8>
J 0
(-6140 4435);
DISPLAY 0.659574 (-6140 4435);
PAINT MONO (-6140 4435);
DISPLAY INVISIBLE (-6140 4435);
FORCEPROP 1 LASTPIN (-6150 4425) BN 8
J 0
(-6162 4433);
DISPLAY 0.489362 (-6162 4433);
PAINT GREEN (-6162 4433);
FORCEPROP 2 LAST CDS_LIB mstr_standard
J 0
(-6100 4425);
DISPLAY 0.723404 (-6100 4425);
PAINT MONO (-6100 4425);
DISPLAY INVISIBLE (-6100 4425);
FORCEPROP 1 LAST BODY_TYPE PLUMBING
J 0
(-6100 4475);
DISPLAY 0.872340 (-6100 4475);
PAINT GREEN (-6100 4475);
DISPLAY INVISIBLE (-6100 4475);
FORCEPROP 1 LAST HDL_TAP TRUE
J 0
(-5775 4300);
DISPLAY 0.872340 (-5775 4300);
DISPLAY INVISIBLE (-5775 4300);
FORCEPROP 1 LAST PATH I111
J 0
(-6102 4425);
DISPLAY 0.872340 (-6102 4425);
PAINT GREEN (-6102 4425);
DISPLAY INVISIBLE (-6102 4425);
FORCEADD TAP..1
(-6100 4475);
FORCEPROP 3 LASTPIN (-6150 4475) SIG_NAME M_D_CPU1_SA_DQ<9>
J 0
(-6140 4485);
DISPLAY 0.659574 (-6140 4485);
PAINT MONO (-6140 4485);
DISPLAY INVISIBLE (-6140 4485);
FORCEPROP 1 LASTPIN (-6150 4475) BN 9
J 0
(-6162 4483);
DISPLAY 0.489362 (-6162 4483);
PAINT GREEN (-6162 4483);
FORCEPROP 2 LAST CDS_LIB mstr_standard
J 0
(-6100 4475);
DISPLAY 0.723404 (-6100 4475);
PAINT MONO (-6100 4475);
DISPLAY INVISIBLE (-6100 4475);
FORCEPROP 1 LAST BODY_TYPE PLUMBING
J 0
(-6100 4525);
DISPLAY 0.872340 (-6100 4525);
PAINT GREEN (-6100 4525);
DISPLAY INVISIBLE (-6100 4525);
FORCEPROP 1 LAST HDL_TAP TRUE
J 0
(-5775 4350);
DISPLAY 0.872340 (-5775 4350);
DISPLAY INVISIBLE (-5775 4350);
FORCEPROP 1 LAST PATH I112
J 0
(-6102 4475);
DISPLAY 0.872340 (-6102 4475);
PAINT GREEN (-6102 4475);
DISPLAY INVISIBLE (-6102 4475);
FORCEADD TAP..1
(-6100 4575);
FORCEPROP 3 LASTPIN (-6150 4575) SIG_NAME M_D_CPU1_SA_DQ<11>
J 0
(-6140 4585);
DISPLAY 0.659574 (-6140 4585);
PAINT MONO (-6140 4585);
DISPLAY INVISIBLE (-6140 4585);
FORCEPROP 1 LASTPIN (-6150 4575) BN 11
J 0
(-6162 4583);
DISPLAY 0.489362 (-6162 4583);
PAINT GREEN (-6162 4583);
FORCEPROP 2 LAST CDS_LIB mstr_standard
J 0
(-6100 4575);
DISPLAY 0.723404 (-6100 4575);
PAINT MONO (-6100 4575);
DISPLAY INVISIBLE (-6100 4575);
FORCEPROP 1 LAST BODY_TYPE PLUMBING
J 0
(-6100 4625);
DISPLAY 0.872340 (-6100 4625);
PAINT GREEN (-6100 4625);
DISPLAY INVISIBLE (-6100 4625);
FORCEPROP 1 LAST HDL_TAP TRUE
J 0
(-5775 4450);
DISPLAY 0.872340 (-5775 4450);
DISPLAY INVISIBLE (-5775 4450);
FORCEPROP 1 LAST PATH I113
J 0
(-6102 4575);
DISPLAY 0.872340 (-6102 4575);
PAINT GREEN (-6102 4575);
DISPLAY INVISIBLE (-6102 4575);
FORCEADD TAP..1
(-6100 4525);
FORCEPROP 3 LASTPIN (-6150 4525) SIG_NAME M_D_CPU1_SA_DQ<10>
J 0
(-6140 4535);
DISPLAY 0.659574 (-6140 4535);
PAINT MONO (-6140 4535);
DISPLAY INVISIBLE (-6140 4535);
FORCEPROP 1 LASTPIN (-6150 4525) BN 10
J 0
(-6162 4533);
DISPLAY 0.489362 (-6162 4533);
PAINT GREEN (-6162 4533);
FORCEPROP 2 LAST CDS_LIB mstr_standard
J 0
(-6100 4525);
DISPLAY 0.723404 (-6100 4525);
PAINT MONO (-6100 4525);
DISPLAY INVISIBLE (-6100 4525);
FORCEPROP 1 LAST BODY_TYPE PLUMBING
J 0
(-6100 4575);
DISPLAY 0.872340 (-6100 4575);
PAINT GREEN (-6100 4575);
DISPLAY INVISIBLE (-6100 4575);
FORCEPROP 1 LAST HDL_TAP TRUE
J 0
(-5775 4400);
DISPLAY 0.872340 (-5775 4400);
DISPLAY INVISIBLE (-5775 4400);
FORCEPROP 1 LAST PATH I114
J 0
(-6102 4525);
DISPLAY 0.872340 (-6102 4525);
PAINT GREEN (-6102 4525);
DISPLAY INVISIBLE (-6102 4525);
FORCEADD TAP..1
(-6100 4625);
FORCEPROP 3 LASTPIN (-6150 4625) SIG_NAME M_D_CPU1_SA_DQ<12>
J 0
(-6140 4635);
DISPLAY 0.659574 (-6140 4635);
PAINT MONO (-6140 4635);
DISPLAY INVISIBLE (-6140 4635);
FORCEPROP 1 LASTPIN (-6150 4625) BN 12
J 0
(-6162 4633);
DISPLAY 0.489362 (-6162 4633);
PAINT GREEN (-6162 4633);
FORCEPROP 2 LAST CDS_LIB mstr_standard
J 0
(-6100 4625);
DISPLAY 0.723404 (-6100 4625);
PAINT MONO (-6100 4625);
DISPLAY INVISIBLE (-6100 4625);
FORCEPROP 1 LAST BODY_TYPE PLUMBING
J 0
(-6100 4675);
DISPLAY 0.872340 (-6100 4675);
PAINT GREEN (-6100 4675);
DISPLAY INVISIBLE (-6100 4675);
FORCEPROP 1 LAST HDL_TAP TRUE
J 0
(-5775 4500);
DISPLAY 0.872340 (-5775 4500);
DISPLAY INVISIBLE (-5775 4500);
FORCEPROP 1 LAST PATH I115
J 0
(-6102 4625);
DISPLAY 0.872340 (-6102 4625);
PAINT GREEN (-6102 4625);
DISPLAY INVISIBLE (-6102 4625);
FORCEADD TAP..1
(-6100 4675);
FORCEPROP 3 LASTPIN (-6150 4675) SIG_NAME M_D_CPU1_SA_DQ<13>
J 0
(-6140 4685);
DISPLAY 0.659574 (-6140 4685);
PAINT MONO (-6140 4685);
DISPLAY INVISIBLE (-6140 4685);
FORCEPROP 1 LASTPIN (-6150 4675) BN 13
J 0
(-6162 4683);
DISPLAY 0.489362 (-6162 4683);
PAINT GREEN (-6162 4683);
FORCEPROP 2 LAST CDS_LIB mstr_standard
J 0
(-6100 4675);
DISPLAY 0.723404 (-6100 4675);
PAINT MONO (-6100 4675);
DISPLAY INVISIBLE (-6100 4675);
FORCEPROP 1 LAST BODY_TYPE PLUMBING
J 0
(-6100 4725);
DISPLAY 0.872340 (-6100 4725);
PAINT GREEN (-6100 4725);
DISPLAY INVISIBLE (-6100 4725);
FORCEPROP 1 LAST HDL_TAP TRUE
J 0
(-5775 4550);
DISPLAY 0.872340 (-5775 4550);
DISPLAY INVISIBLE (-5775 4550);
FORCEPROP 1 LAST PATH I116
J 0
(-6102 4675);
DISPLAY 0.872340 (-6102 4675);
PAINT GREEN (-6102 4675);
DISPLAY INVISIBLE (-6102 4675);
FORCEADD TAP..1
(-6100 4725);
FORCEPROP 3 LASTPIN (-6150 4725) SIG_NAME M_D_CPU1_SA_DQ<14>
J 0
(-6140 4735);
DISPLAY 0.659574 (-6140 4735);
PAINT MONO (-6140 4735);
DISPLAY INVISIBLE (-6140 4735);
FORCEPROP 1 LASTPIN (-6150 4725) BN 14
J 0
(-6162 4733);
DISPLAY 0.489362 (-6162 4733);
PAINT GREEN (-6162 4733);
FORCEPROP 2 LAST CDS_LIB mstr_standard
J 0
(-6100 4725);
DISPLAY 0.723404 (-6100 4725);
PAINT MONO (-6100 4725);
DISPLAY INVISIBLE (-6100 4725);
FORCEPROP 1 LAST BODY_TYPE PLUMBING
J 0
(-6100 4775);
DISPLAY 0.872340 (-6100 4775);
PAINT GREEN (-6100 4775);
DISPLAY INVISIBLE (-6100 4775);
FORCEPROP 1 LAST HDL_TAP TRUE
J 0
(-5775 4600);
DISPLAY 0.872340 (-5775 4600);
DISPLAY INVISIBLE (-5775 4600);
FORCEPROP 1 LAST PATH I117
J 0
(-6102 4725);
DISPLAY 0.872340 (-6102 4725);
PAINT GREEN (-6102 4725);
DISPLAY INVISIBLE (-6102 4725);
FORCEADD TAP..1
(-6100 4825);
FORCEPROP 3 LASTPIN (-6150 4825) SIG_NAME M_D_CPU1_SA_DQ<16>
J 0
(-6140 4835);
DISPLAY 0.659574 (-6140 4835);
PAINT MONO (-6140 4835);
DISPLAY INVISIBLE (-6140 4835);
FORCEPROP 1 LASTPIN (-6150 4825) BN 16
J 0
(-6162 4833);
DISPLAY 0.489362 (-6162 4833);
PAINT GREEN (-6162 4833);
FORCEPROP 2 LAST CDS_LIB mstr_standard
J 0
(-6100 4825);
DISPLAY 0.723404 (-6100 4825);
PAINT MONO (-6100 4825);
DISPLAY INVISIBLE (-6100 4825);
FORCEPROP 1 LAST BODY_TYPE PLUMBING
J 0
(-6100 4875);
DISPLAY 0.872340 (-6100 4875);
PAINT GREEN (-6100 4875);
DISPLAY INVISIBLE (-6100 4875);
FORCEPROP 1 LAST HDL_TAP TRUE
J 0
(-5775 4700);
DISPLAY 0.872340 (-5775 4700);
DISPLAY INVISIBLE (-5775 4700);
FORCEPROP 1 LAST PATH I118
J 0
(-6102 4825);
DISPLAY 0.872340 (-6102 4825);
PAINT GREEN (-6102 4825);
DISPLAY INVISIBLE (-6102 4825);
FORCEADD TAP..1
(-6100 4775);
FORCEPROP 3 LASTPIN (-6150 4775) SIG_NAME M_D_CPU1_SA_DQ<15>
J 0
(-6140 4785);
DISPLAY 0.659574 (-6140 4785);
PAINT MONO (-6140 4785);
DISPLAY INVISIBLE (-6140 4785);
FORCEPROP 1 LASTPIN (-6150 4775) BN 15
J 0
(-6162 4783);
DISPLAY 0.489362 (-6162 4783);
PAINT GREEN (-6162 4783);
FORCEPROP 2 LAST CDS_LIB mstr_standard
J 0
(-6100 4775);
DISPLAY 0.723404 (-6100 4775);
PAINT MONO (-6100 4775);
DISPLAY INVISIBLE (-6100 4775);
FORCEPROP 1 LAST BODY_TYPE PLUMBING
J 0
(-6100 4825);
DISPLAY 0.872340 (-6100 4825);
PAINT GREEN (-6100 4825);
DISPLAY INVISIBLE (-6100 4825);
FORCEPROP 1 LAST HDL_TAP TRUE
J 0
(-5775 4650);
DISPLAY 0.872340 (-5775 4650);
DISPLAY INVISIBLE (-5775 4650);
FORCEPROP 1 LAST PATH I119
J 0
(-6102 4775);
DISPLAY 0.872340 (-6102 4775);
PAINT GREEN (-6102 4775);
DISPLAY INVISIBLE (-6102 4775);
FORCEADD TAP..1
R 2
(-7800 3425);
FORCEPROP 3 LASTPIN (-7750 3425) SIG_NAME M_D_CPU1_SB_CB<1>
J 0
(-7740 3435);
DISPLAY 0.659574 (-7740 3435);
PAINT MONO (-7740 3435);
DISPLAY INVISIBLE (-7740 3435);
FORCEPROP 1 LASTPIN (-7750 3425) BN 1
J 2
(-7738 3433);
DISPLAY 0.489362 (-7738 3433);
PAINT GREEN (-7738 3433);
FORCEPROP 2 LAST CDS_LIB mstr_standard
J 0
(-7800 3425);
DISPLAY 0.723404 (-7800 3425);
PAINT MONO (-7800 3425);
DISPLAY INVISIBLE (-7800 3425);
FORCEPROP 1 LAST BODY_TYPE PLUMBING
J 2
(-7800 3475);
DISPLAY 0.872340 (-7800 3475);
PAINT GREEN (-7800 3475);
DISPLAY INVISIBLE (-7800 3475);
FORCEPROP 1 LAST HDL_TAP TRUE
J 2
(-8125 3300);
DISPLAY 0.872340 (-8125 3300);
DISPLAY INVISIBLE (-8125 3300);
FORCEPROP 1 LAST PATH I12
J 2
(-7798 3425);
DISPLAY 0.872340 (-7798 3425);
PAINT GREEN (-7798 3425);
DISPLAY INVISIBLE (-7798 3425);
FORCEADD TAP..1
(-6100 4875);
FORCEPROP 3 LASTPIN (-6150 4875) SIG_NAME M_D_CPU1_SA_DQ<17>
J 0
(-6140 4885);
DISPLAY 0.659574 (-6140 4885);
PAINT MONO (-6140 4885);
DISPLAY INVISIBLE (-6140 4885);
FORCEPROP 1 LASTPIN (-6150 4875) BN 17
J 0
(-6162 4883);
DISPLAY 0.489362 (-6162 4883);
PAINT GREEN (-6162 4883);
FORCEPROP 2 LAST CDS_LIB mstr_standard
J 0
(-6100 4875);
DISPLAY 0.723404 (-6100 4875);
PAINT MONO (-6100 4875);
DISPLAY INVISIBLE (-6100 4875);
FORCEPROP 1 LAST BODY_TYPE PLUMBING
J 0
(-6100 4925);
DISPLAY 0.872340 (-6100 4925);
PAINT GREEN (-6100 4925);
DISPLAY INVISIBLE (-6100 4925);
FORCEPROP 1 LAST HDL_TAP TRUE
J 0
(-5775 4750);
DISPLAY 0.872340 (-5775 4750);
DISPLAY INVISIBLE (-5775 4750);
FORCEPROP 1 LAST PATH I120
J 0
(-6102 4875);
DISPLAY 0.872340 (-6102 4875);
PAINT GREEN (-6102 4875);
DISPLAY INVISIBLE (-6102 4875);
FORCEADD TAP..1
(-6100 4925);
FORCEPROP 3 LASTPIN (-6150 4925) SIG_NAME M_D_CPU1_SA_DQ<18>
J 0
(-6140 4935);
DISPLAY 0.659574 (-6140 4935);
PAINT MONO (-6140 4935);
DISPLAY INVISIBLE (-6140 4935);
FORCEPROP 1 LASTPIN (-6150 4925) BN 18
J 0
(-6162 4933);
DISPLAY 0.489362 (-6162 4933);
PAINT GREEN (-6162 4933);
FORCEPROP 2 LAST CDS_LIB mstr_standard
J 0
(-6100 4925);
DISPLAY 0.723404 (-6100 4925);
PAINT MONO (-6100 4925);
DISPLAY INVISIBLE (-6100 4925);
FORCEPROP 1 LAST BODY_TYPE PLUMBING
J 0
(-6100 4975);
DISPLAY 0.872340 (-6100 4975);
PAINT GREEN (-6100 4975);
DISPLAY INVISIBLE (-6100 4975);
FORCEPROP 1 LAST HDL_TAP TRUE
J 0
(-5775 4800);
DISPLAY 0.872340 (-5775 4800);
DISPLAY INVISIBLE (-5775 4800);
FORCEPROP 1 LAST PATH I121
J 0
(-6102 4925);
DISPLAY 0.872340 (-6102 4925);
PAINT GREEN (-6102 4925);
DISPLAY INVISIBLE (-6102 4925);
FORCEADD TAP..1
(-6100 5025);
FORCEPROP 3 LASTPIN (-6150 5025) SIG_NAME M_D_CPU1_SA_DQ<20>
J 0
(-6140 5035);
DISPLAY 0.659574 (-6140 5035);
PAINT MONO (-6140 5035);
DISPLAY INVISIBLE (-6140 5035);
FORCEPROP 1 LASTPIN (-6150 5025) BN 20
J 0
(-6162 5033);
DISPLAY 0.489362 (-6162 5033);
PAINT GREEN (-6162 5033);
FORCEPROP 2 LAST CDS_LIB mstr_standard
J 0
(-6100 5025);
DISPLAY 0.723404 (-6100 5025);
PAINT MONO (-6100 5025);
DISPLAY INVISIBLE (-6100 5025);
FORCEPROP 1 LAST BODY_TYPE PLUMBING
J 0
(-6100 5075);
DISPLAY 0.872340 (-6100 5075);
PAINT GREEN (-6100 5075);
DISPLAY INVISIBLE (-6100 5075);
FORCEPROP 1 LAST HDL_TAP TRUE
J 0
(-5775 4900);
DISPLAY 0.872340 (-5775 4900);
DISPLAY INVISIBLE (-5775 4900);
FORCEPROP 1 LAST PATH I122
J 0
(-6102 5025);
DISPLAY 0.872340 (-6102 5025);
PAINT GREEN (-6102 5025);
DISPLAY INVISIBLE (-6102 5025);
FORCEADD TAP..1
(-6100 4975);
FORCEPROP 3 LASTPIN (-6150 4975) SIG_NAME M_D_CPU1_SA_DQ<19>
J 0
(-6140 4985);
DISPLAY 0.659574 (-6140 4985);
PAINT MONO (-6140 4985);
DISPLAY INVISIBLE (-6140 4985);
FORCEPROP 1 LASTPIN (-6150 4975) BN 19
J 0
(-6162 4983);
DISPLAY 0.489362 (-6162 4983);
PAINT GREEN (-6162 4983);
FORCEPROP 2 LAST CDS_LIB mstr_standard
J 0
(-6100 4975);
DISPLAY 0.723404 (-6100 4975);
PAINT MONO (-6100 4975);
DISPLAY INVISIBLE (-6100 4975);
FORCEPROP 1 LAST BODY_TYPE PLUMBING
J 0
(-6100 5025);
DISPLAY 0.872340 (-6100 5025);
PAINT GREEN (-6100 5025);
DISPLAY INVISIBLE (-6100 5025);
FORCEPROP 1 LAST HDL_TAP TRUE
J 0
(-5775 4850);
DISPLAY 0.872340 (-5775 4850);
DISPLAY INVISIBLE (-5775 4850);
FORCEPROP 1 LAST PATH I123
J 0
(-6102 4975);
DISPLAY 0.872340 (-6102 4975);
PAINT GREEN (-6102 4975);
DISPLAY INVISIBLE (-6102 4975);
FORCEADD TAP..1
(-6100 5075);
FORCEPROP 3 LASTPIN (-6150 5075) SIG_NAME M_D_CPU1_SA_DQ<21>
J 0
(-6140 5085);
DISPLAY 0.659574 (-6140 5085);
PAINT MONO (-6140 5085);
DISPLAY INVISIBLE (-6140 5085);
FORCEPROP 1 LASTPIN (-6150 5075) BN 21
J 0
(-6162 5083);
DISPLAY 0.489362 (-6162 5083);
PAINT GREEN (-6162 5083);
FORCEPROP 2 LAST CDS_LIB mstr_standard
J 0
(-6100 5075);
DISPLAY 0.723404 (-6100 5075);
PAINT MONO (-6100 5075);
DISPLAY INVISIBLE (-6100 5075);
FORCEPROP 1 LAST BODY_TYPE PLUMBING
J 0
(-6100 5125);
DISPLAY 0.872340 (-6100 5125);
PAINT GREEN (-6100 5125);
DISPLAY INVISIBLE (-6100 5125);
FORCEPROP 1 LAST HDL_TAP TRUE
J 0
(-5775 4950);
DISPLAY 0.872340 (-5775 4950);
DISPLAY INVISIBLE (-5775 4950);
FORCEPROP 1 LAST PATH I124
J 0
(-6102 5075);
DISPLAY 0.872340 (-6102 5075);
PAINT GREEN (-6102 5075);
DISPLAY INVISIBLE (-6102 5075);
FORCEADD TAP..1
(-6100 5125);
FORCEPROP 3 LASTPIN (-6150 5125) SIG_NAME M_D_CPU1_SA_DQ<22>
J 0
(-6140 5135);
DISPLAY 0.659574 (-6140 5135);
PAINT MONO (-6140 5135);
DISPLAY INVISIBLE (-6140 5135);
FORCEPROP 1 LASTPIN (-6150 5125) BN 22
J 0
(-6162 5133);
DISPLAY 0.489362 (-6162 5133);
PAINT GREEN (-6162 5133);
FORCEPROP 2 LAST CDS_LIB mstr_standard
J 0
(-6100 5125);
DISPLAY 0.723404 (-6100 5125);
PAINT MONO (-6100 5125);
DISPLAY INVISIBLE (-6100 5125);
FORCEPROP 1 LAST BODY_TYPE PLUMBING
J 0
(-6100 5175);
DISPLAY 0.872340 (-6100 5175);
PAINT GREEN (-6100 5175);
DISPLAY INVISIBLE (-6100 5175);
FORCEPROP 1 LAST HDL_TAP TRUE
J 0
(-5775 5000);
DISPLAY 0.872340 (-5775 5000);
DISPLAY INVISIBLE (-5775 5000);
FORCEPROP 1 LAST PATH I125
J 0
(-6102 5125);
DISPLAY 0.872340 (-6102 5125);
PAINT GREEN (-6102 5125);
DISPLAY INVISIBLE (-6102 5125);
FORCEADD TAP..1
(-6100 5175);
FORCEPROP 3 LASTPIN (-6150 5175) SIG_NAME M_D_CPU1_SA_DQ<23>
J 0
(-6140 5185);
DISPLAY 0.659574 (-6140 5185);
PAINT MONO (-6140 5185);
DISPLAY INVISIBLE (-6140 5185);
FORCEPROP 1 LASTPIN (-6150 5175) BN 23
J 0
(-6162 5183);
DISPLAY 0.489362 (-6162 5183);
PAINT GREEN (-6162 5183);
FORCEPROP 2 LAST CDS_LIB mstr_standard
J 0
(-6100 5175);
DISPLAY 0.723404 (-6100 5175);
PAINT MONO (-6100 5175);
DISPLAY INVISIBLE (-6100 5175);
FORCEPROP 1 LAST BODY_TYPE PLUMBING
J 0
(-6100 5225);
DISPLAY 0.872340 (-6100 5225);
PAINT GREEN (-6100 5225);
DISPLAY INVISIBLE (-6100 5225);
FORCEPROP 1 LAST HDL_TAP TRUE
J 0
(-5775 5050);
DISPLAY 0.872340 (-5775 5050);
DISPLAY INVISIBLE (-5775 5050);
FORCEPROP 1 LAST PATH I126
J 0
(-6102 5175);
DISPLAY 0.872340 (-6102 5175);
PAINT GREEN (-6102 5175);
DISPLAY INVISIBLE (-6102 5175);
FORCEADD TAP..1
(-6100 5275);
FORCEPROP 3 LASTPIN (-6150 5275) SIG_NAME M_D_CPU1_SA_DQ<25>
J 0
(-6140 5285);
DISPLAY 0.659574 (-6140 5285);
PAINT MONO (-6140 5285);
DISPLAY INVISIBLE (-6140 5285);
FORCEPROP 1 LASTPIN (-6150 5275) BN 25
J 0
(-6162 5283);
DISPLAY 0.489362 (-6162 5283);
PAINT GREEN (-6162 5283);
FORCEPROP 2 LAST CDS_LIB mstr_standard
J 0
(-6100 5275);
DISPLAY 0.723404 (-6100 5275);
PAINT MONO (-6100 5275);
DISPLAY INVISIBLE (-6100 5275);
FORCEPROP 1 LAST BODY_TYPE PLUMBING
J 0
(-6100 5325);
DISPLAY 0.872340 (-6100 5325);
PAINT GREEN (-6100 5325);
DISPLAY INVISIBLE (-6100 5325);
FORCEPROP 1 LAST HDL_TAP TRUE
J 0
(-5775 5150);
DISPLAY 0.872340 (-5775 5150);
DISPLAY INVISIBLE (-5775 5150);
FORCEPROP 1 LAST PATH I127
J 0
(-6102 5275);
DISPLAY 0.872340 (-6102 5275);
PAINT GREEN (-6102 5275);
DISPLAY INVISIBLE (-6102 5275);
FORCEADD TAP..1
(-6100 5225);
FORCEPROP 3 LASTPIN (-6150 5225) SIG_NAME M_D_CPU1_SA_DQ<24>
J 0
(-6140 5235);
DISPLAY 0.659574 (-6140 5235);
PAINT MONO (-6140 5235);
DISPLAY INVISIBLE (-6140 5235);
FORCEPROP 1 LASTPIN (-6150 5225) BN 24
J 0
(-6162 5233);
DISPLAY 0.489362 (-6162 5233);
PAINT GREEN (-6162 5233);
FORCEPROP 2 LAST CDS_LIB mstr_standard
J 0
(-6100 5225);
DISPLAY 0.723404 (-6100 5225);
PAINT MONO (-6100 5225);
DISPLAY INVISIBLE (-6100 5225);
FORCEPROP 1 LAST BODY_TYPE PLUMBING
J 0
(-6100 5275);
DISPLAY 0.872340 (-6100 5275);
PAINT GREEN (-6100 5275);
DISPLAY INVISIBLE (-6100 5275);
FORCEPROP 1 LAST HDL_TAP TRUE
J 0
(-5775 5100);
DISPLAY 0.872340 (-5775 5100);
DISPLAY INVISIBLE (-5775 5100);
FORCEPROP 1 LAST PATH I128
J 0
(-6102 5225);
DISPLAY 0.872340 (-6102 5225);
PAINT GREEN (-6102 5225);
DISPLAY INVISIBLE (-6102 5225);
FORCEADD TAP..1
(-6100 5325);
FORCEPROP 3 LASTPIN (-6150 5325) SIG_NAME M_D_CPU1_SA_DQ<26>
J 0
(-6140 5335);
DISPLAY 0.659574 (-6140 5335);
PAINT MONO (-6140 5335);
DISPLAY INVISIBLE (-6140 5335);
FORCEPROP 1 LASTPIN (-6150 5325) BN 26
J 0
(-6162 5333);
DISPLAY 0.489362 (-6162 5333);
PAINT GREEN (-6162 5333);
FORCEPROP 2 LAST CDS_LIB mstr_standard
J 0
(-6100 5325);
DISPLAY 0.723404 (-6100 5325);
PAINT MONO (-6100 5325);
DISPLAY INVISIBLE (-6100 5325);
FORCEPROP 1 LAST BODY_TYPE PLUMBING
J 0
(-6100 5375);
DISPLAY 0.872340 (-6100 5375);
PAINT GREEN (-6100 5375);
DISPLAY INVISIBLE (-6100 5375);
FORCEPROP 1 LAST HDL_TAP TRUE
J 0
(-5775 5200);
DISPLAY 0.872340 (-5775 5200);
DISPLAY INVISIBLE (-5775 5200);
FORCEPROP 1 LAST PATH I129
J 0
(-6102 5325);
DISPLAY 0.872340 (-6102 5325);
PAINT GREEN (-6102 5325);
DISPLAY INVISIBLE (-6102 5325);
FORCEADD TAP..1
R 2
(-7800 3375);
FORCEPROP 3 LASTPIN (-7750 3375) SIG_NAME M_D_CPU1_SB_CB<0>
J 0
(-7740 3385);
DISPLAY 0.659574 (-7740 3385);
PAINT MONO (-7740 3385);
DISPLAY INVISIBLE (-7740 3385);
FORCEPROP 1 LASTPIN (-7750 3375) BN 0
J 2
(-7738 3383);
DISPLAY 0.489362 (-7738 3383);
PAINT GREEN (-7738 3383);
FORCEPROP 2 LAST CDS_LIB mstr_standard
J 0
(-7800 3375);
DISPLAY 0.723404 (-7800 3375);
PAINT MONO (-7800 3375);
DISPLAY INVISIBLE (-7800 3375);
FORCEPROP 1 LAST BODY_TYPE PLUMBING
J 2
(-7800 3425);
DISPLAY 0.872340 (-7800 3425);
PAINT GREEN (-7800 3425);
DISPLAY INVISIBLE (-7800 3425);
FORCEPROP 1 LAST HDL_TAP TRUE
J 2
(-8125 3250);
DISPLAY 0.872340 (-8125 3250);
DISPLAY INVISIBLE (-8125 3250);
FORCEPROP 1 LAST PATH I13
J 2
(-7798 3375);
DISPLAY 0.872340 (-7798 3375);
PAINT GREEN (-7798 3375);
DISPLAY INVISIBLE (-7798 3375);
FORCEADD TAP..1
(-6100 5375);
FORCEPROP 3 LASTPIN (-6150 5375) SIG_NAME M_D_CPU1_SA_DQ<27>
J 0
(-6140 5385);
DISPLAY 0.659574 (-6140 5385);
PAINT MONO (-6140 5385);
DISPLAY INVISIBLE (-6140 5385);
FORCEPROP 1 LASTPIN (-6150 5375) BN 27
J 0
(-6162 5383);
DISPLAY 0.489362 (-6162 5383);
PAINT GREEN (-6162 5383);
FORCEPROP 2 LAST CDS_LIB mstr_standard
J 0
(-6100 5375);
DISPLAY 0.723404 (-6100 5375);
PAINT MONO (-6100 5375);
DISPLAY INVISIBLE (-6100 5375);
FORCEPROP 1 LAST BODY_TYPE PLUMBING
J 0
(-6100 5425);
DISPLAY 0.872340 (-6100 5425);
PAINT GREEN (-6100 5425);
DISPLAY INVISIBLE (-6100 5425);
FORCEPROP 1 LAST HDL_TAP TRUE
J 0
(-5775 5250);
DISPLAY 0.872340 (-5775 5250);
DISPLAY INVISIBLE (-5775 5250);
FORCEPROP 1 LAST PATH I130
J 0
(-6102 5375);
DISPLAY 0.872340 (-6102 5375);
PAINT GREEN (-6102 5375);
DISPLAY INVISIBLE (-6102 5375);
FORCEADD TAP..1
(-6100 5475);
FORCEPROP 3 LASTPIN (-6150 5475) SIG_NAME M_D_CPU1_SA_DQ<29>
J 0
(-6140 5485);
DISPLAY 0.659574 (-6140 5485);
PAINT MONO (-6140 5485);
DISPLAY INVISIBLE (-6140 5485);
FORCEPROP 1 LASTPIN (-6150 5475) BN 29
J 0
(-6162 5483);
DISPLAY 0.489362 (-6162 5483);
PAINT GREEN (-6162 5483);
FORCEPROP 2 LAST CDS_LIB mstr_standard
J 0
(-6100 5475);
DISPLAY 0.723404 (-6100 5475);
PAINT MONO (-6100 5475);
DISPLAY INVISIBLE (-6100 5475);
FORCEPROP 1 LAST BODY_TYPE PLUMBING
J 0
(-6100 5525);
DISPLAY 0.872340 (-6100 5525);
PAINT GREEN (-6100 5525);
DISPLAY INVISIBLE (-6100 5525);
FORCEPROP 1 LAST HDL_TAP TRUE
J 0
(-5775 5350);
DISPLAY 0.872340 (-5775 5350);
DISPLAY INVISIBLE (-5775 5350);
FORCEPROP 1 LAST PATH I131
J 0
(-6102 5475);
DISPLAY 0.872340 (-6102 5475);
PAINT GREEN (-6102 5475);
DISPLAY INVISIBLE (-6102 5475);
FORCEADD TAP..1
(-6100 5425);
FORCEPROP 3 LASTPIN (-6150 5425) SIG_NAME M_D_CPU1_SA_DQ<28>
J 0
(-6140 5435);
DISPLAY 0.659574 (-6140 5435);
PAINT MONO (-6140 5435);
DISPLAY INVISIBLE (-6140 5435);
FORCEPROP 1 LASTPIN (-6150 5425) BN 28
J 0
(-6162 5433);
DISPLAY 0.489362 (-6162 5433);
PAINT GREEN (-6162 5433);
FORCEPROP 2 LAST CDS_LIB mstr_standard
J 0
(-6100 5425);
DISPLAY 0.723404 (-6100 5425);
PAINT MONO (-6100 5425);
DISPLAY INVISIBLE (-6100 5425);
FORCEPROP 1 LAST BODY_TYPE PLUMBING
J 0
(-6100 5475);
DISPLAY 0.872340 (-6100 5475);
PAINT GREEN (-6100 5475);
DISPLAY INVISIBLE (-6100 5475);
FORCEPROP 1 LAST HDL_TAP TRUE
J 0
(-5775 5300);
DISPLAY 0.872340 (-5775 5300);
DISPLAY INVISIBLE (-5775 5300);
FORCEPROP 1 LAST PATH I132
J 0
(-6102 5425);
DISPLAY 0.872340 (-6102 5425);
PAINT GREEN (-6102 5425);
DISPLAY INVISIBLE (-6102 5425);
FORCEADD TAP..1
(-6100 5525);
FORCEPROP 3 LASTPIN (-6150 5525) SIG_NAME M_D_CPU1_SA_DQ<30>
J 0
(-6140 5535);
DISPLAY 0.659574 (-6140 5535);
PAINT MONO (-6140 5535);
DISPLAY INVISIBLE (-6140 5535);
FORCEPROP 1 LASTPIN (-6150 5525) BN 30
J 0
(-6162 5533);
DISPLAY 0.489362 (-6162 5533);
PAINT GREEN (-6162 5533);
FORCEPROP 2 LAST CDS_LIB mstr_standard
J 0
(-6100 5525);
DISPLAY 0.723404 (-6100 5525);
PAINT MONO (-6100 5525);
DISPLAY INVISIBLE (-6100 5525);
FORCEPROP 1 LAST BODY_TYPE PLUMBING
J 0
(-6100 5575);
DISPLAY 0.872340 (-6100 5575);
PAINT GREEN (-6100 5575);
DISPLAY INVISIBLE (-6100 5575);
FORCEPROP 1 LAST HDL_TAP TRUE
J 0
(-5775 5400);
DISPLAY 0.872340 (-5775 5400);
DISPLAY INVISIBLE (-5775 5400);
FORCEPROP 1 LAST PATH I133
J 0
(-6102 5525);
DISPLAY 0.872340 (-6102 5525);
PAINT GREEN (-6102 5525);
DISPLAY INVISIBLE (-6102 5525);
FORCEADD TAP..1
(-6100 5575);
FORCEPROP 3 LASTPIN (-6150 5575) SIG_NAME M_D_CPU1_SA_DQ<31>
J 0
(-6140 5585);
DISPLAY 0.659574 (-6140 5585);
PAINT MONO (-6140 5585);
DISPLAY INVISIBLE (-6140 5585);
FORCEPROP 1 LASTPIN (-6150 5575) BN 31
J 0
(-6162 5583);
DISPLAY 0.489362 (-6162 5583);
PAINT GREEN (-6162 5583);
FORCEPROP 2 LAST CDS_LIB mstr_standard
J 0
(-6100 5575);
DISPLAY 0.723404 (-6100 5575);
PAINT MONO (-6100 5575);
DISPLAY INVISIBLE (-6100 5575);
FORCEPROP 1 LAST BODY_TYPE PLUMBING
J 0
(-6100 5625);
DISPLAY 0.872340 (-6100 5625);
PAINT GREEN (-6100 5625);
DISPLAY INVISIBLE (-6100 5625);
FORCEPROP 1 LAST HDL_TAP TRUE
J 0
(-5775 5450);
DISPLAY 0.872340 (-5775 5450);
DISPLAY INVISIBLE (-5775 5450);
FORCEPROP 1 LAST PATH I134
J 0
(-6102 5575);
DISPLAY 0.872340 (-6102 5575);
PAINT GREEN (-6102 5575);
DISPLAY INVISIBLE (-6102 5575);
FORCEADD OFFPAGE..3
(-5425 5625);
FORCEPROP 2 LAST $XR0 40 
J 0
(-5211 5625);
DISPLAY 0.638298 (-5211 5625);
PAINT MONO (-5211 5625);
FORCEPROP 2 LAST CDS_LIB mstr_standard
J 0
(-5425 5625);
DISPLAY 0.723404 (-5425 5625);
PAINT MONO (-5425 5625);
DISPLAY INVISIBLE (-5425 5625);
FORCEPROP 1 LAST OFFPAGE TRUE
J 0
(-5100 5500);
DISPLAY 0.872340 (-5100 5500);
PAINT GREEN (-5100 5500);
DISPLAY INVISIBLE (-5100 5500);
FORCEPROP 1 LAST COMMENT_BODY TRUE
J 0
(-5475 5525);
DISPLAY 0.872340 (-5475 5525);
PAINT GREEN (-5475 5525);
DISPLAY INVISIBLE (-5475 5525);
FORCEPROP 2 LAST PATH I135
J 0
(-5200 5675);
DISPLAY 1.021277 (-5200 5675);
DISPLAY INVISIBLE (-5200 5675);
FORCEADD TAP..1
R 2
(-7800 3525);
FORCEPROP 3 LASTPIN (-7750 3525) SIG_NAME M_D_CPU1_SB_CB<3>
J 0
(-7740 3535);
DISPLAY 0.659574 (-7740 3535);
PAINT MONO (-7740 3535);
DISPLAY INVISIBLE (-7740 3535);
FORCEPROP 1 LASTPIN (-7750 3525) BN 3
J 2
(-7738 3533);
DISPLAY 0.489362 (-7738 3533);
PAINT GREEN (-7738 3533);
FORCEPROP 2 LAST CDS_LIB mstr_standard
J 0
(-7800 3525);
DISPLAY 0.723404 (-7800 3525);
PAINT MONO (-7800 3525);
DISPLAY INVISIBLE (-7800 3525);
FORCEPROP 1 LAST BODY_TYPE PLUMBING
J 2
(-7800 3575);
DISPLAY 0.872340 (-7800 3575);
PAINT GREEN (-7800 3575);
DISPLAY INVISIBLE (-7800 3575);
FORCEPROP 1 LAST HDL_TAP TRUE
J 2
(-8125 3400);
DISPLAY 0.872340 (-8125 3400);
DISPLAY INVISIBLE (-8125 3400);
FORCEPROP 1 LAST PATH I14
J 2
(-7798 3525);
DISPLAY 0.872340 (-7798 3525);
PAINT GREEN (-7798 3525);
DISPLAY INVISIBLE (-7798 3525);
FORCEADD GND..1
(-6525 1200);
FORCEPROP 3 LASTPIN (-6525 1250) SIG_NAME GND\g
J 0
(-6515 1260);
DISPLAY 0.659574 (-6515 1260);
PAINT MONO (-6515 1260);
DISPLAY INVISIBLE (-6515 1260);
FORCEPROP 1 LAST VOLTAGE 0.0
J 0
(-6570 1157);
DISPLAY 0.723404 (-6570 1157);
PAINT SKYBLUE (-6570 1157);
DISPLAY INVISIBLE (-6570 1157);
FORCEPROP 2 LAST CDS_LIB mstr_symbols
J 0
(-6525 1200);
DISPLAY 0.808511 (-6525 1200);
DISPLAY INVISIBLE (-6525 1200);
FORCEPROP 2 LAST BOM_COST MEM
J 0
(-6625 1275);
DISPLAY 0.808511 (-6625 1275);
DISPLAY INVISIBLE (-6625 1275);
FORCEPROP 1 LAST SIZE 1B
J 0
(-6450 1150);
DISPLAY 0.851064 (-6450 1150);
PAINT GREEN (-6450 1150);
DISPLAY INVISIBLE (-6450 1150);
FORCEPROP 1 LAST BODY_TYPE PLUMBING
J 0
(-6570 1157);
DISPLAY 0.340426 (-6570 1157);
PAINT GREEN (-6570 1157);
DISPLAY INVISIBLE (-6570 1157);
FORCEPROP 1 LAST HDL_POWER GND
J 0
(-6525 1350);
DISPLAY 0.851064 (-6525 1350);
PAINT GREEN (-6525 1350);
DISPLAY INVISIBLE (-6525 1350);
FORCEPROP 1 LAST PATH I145
J 0
(-6450 1200);
DISPLAY 0.872340 (-6450 1200);
PAINT AQUA (-6450 1200);
DISPLAY INVISIBLE (-6450 1200);
FORCEADD Q_RES..2
(-6525 1425);
FORCEPROP 1 LAST LOCATION R772
J 0
(-6480 1550);
DISPLAY 0.489362 (-6480 1550);
PAINT SKYBLUE (-6480 1550);
FORCEPROP 0 LAST $SEC 1
J 0
(-6475 1600);
DISPLAY 0.680851 (-6475 1600);
PAINT MONO (-6475 1600);
DISPLAY INVISIBLE (-6475 1600);
FORCEPROP 0 LAST CDS_SEC 1
J 0
(-6475 1600);
DISPLAY 1.021277 (-6475 1600);
DISPLAY INVISIBLE (-6475 1600);
FORCEPROP 1 LASTPIN (-6525 1525) $PN 1
J 0
(-6520 1487);
DISPLAY 0.489362 (-6520 1487);
PAINT MONO (-6520 1487);
FORCEPROP 1 LASTPIN (-6525 1325) $PN 2
J 0
(-6520 1335);
DISPLAY 0.489362 (-6520 1335);
PAINT MONO (-6520 1335);
FORCEPROP 1 LAST PACK_TYPE 0402LF
J 0
(-6485 1250);
DISPLAY 0.489362 (-6485 1250);
PAINT SKYBLUE (-6485 1250);
FORCEPROP 1 LAST VALUE 35.7K
J 0
(-6480 1500);
DISPLAY 0.489362 (-6480 1500);
PAINT SKYBLUE (-6480 1500);
FORCEPROP 1 LAST TOLERANCE 1%
J 0
(-6480 1450);
DISPLAY 0.489362 (-6480 1450);
PAINT SKYBLUE (-6480 1450);
FORCEPROP 1 LAST MATERIAL CHIP
J 0
(-6485 1350);
DISPLAY 0.489362 (-6485 1350);
PAINT SKYBLUE (-6485 1350);
FORCEPROP 1 LAST WATTAGE 1/16W
J 0
(-6485 1400);
DISPLAY 0.489362 (-6485 1400);
PAINT SKYBLUE (-6485 1400);
FORCEPROP 2 LAST CDS_LIB pure_quanta
J 0
(-6525 1425);
DISPLAY INVISIBLE (-6525 1425);
FORCEPROP 1 LAST PATH I146
J 0
(-6475 1600);
DISPLAY 0.978723 (-6475 1600);
PAINT WHITE (-6475 1600);
DISPLAY INVISIBLE (-6475 1600);
FORCEPROP 1 LAST PART_NUMBER CS33572FB01
J 0
(-6485 1300);
DISPLAY 0.489362 (-6485 1300);
PAINT SKYBLUE (-6485 1300);
DISPLAY INVISIBLE (-6485 1300);
FORCEADD GND..1
(-2200 2000);
FORCEPROP 3 LASTPIN (-2200 2050) SIG_NAME GND\g
J 0
(-2190 2060);
DISPLAY 0.659574 (-2190 2060);
PAINT MONO (-2190 2060);
DISPLAY INVISIBLE (-2190 2060);
FORCEPROP 1 LAST VOLTAGE 0.0
J 0
(-2245 1957);
DISPLAY 0.723404 (-2245 1957);
PAINT SKYBLUE (-2245 1957);
DISPLAY INVISIBLE (-2245 1957);
FORCEPROP 1 LAST SIZE 1B
J 0
(-2125 1950);
DISPLAY 0.851064 (-2125 1950);
PAINT GREEN (-2125 1950);
DISPLAY INVISIBLE (-2125 1950);
FORCEPROP 2 LAST CDS_LIB mstr_symbols
J 0
(-2200 2000);
DISPLAY 0.723404 (-2200 2000);
DISPLAY INVISIBLE (-2200 2000);
FORCEPROP 1 LAST BODY_TYPE PLUMBING
J 0
(-2245 1957);
DISPLAY 0.340426 (-2245 1957);
PAINT GREEN (-2245 1957);
DISPLAY INVISIBLE (-2245 1957);
FORCEPROP 1 LAST HDL_POWER GND
J 0
(-2200 2150);
DISPLAY 0.851064 (-2200 2150);
PAINT GREEN (-2200 2150);
DISPLAY INVISIBLE (-2200 2150);
FORCEPROP 1 LAST PATH I147
J 0
(-2125 2000);
DISPLAY 0.872340 (-2125 2000);
PAINT AQUA (-2125 2000);
DISPLAY INVISIBLE (-2125 2000);
FORCEADD TAP..1
R 2
(-7800 3475);
FORCEPROP 3 LASTPIN (-7750 3475) SIG_NAME M_D_CPU1_SB_CB<2>
J 0
(-7740 3485);
DISPLAY 0.659574 (-7740 3485);
PAINT MONO (-7740 3485);
DISPLAY INVISIBLE (-7740 3485);
FORCEPROP 1 LASTPIN (-7750 3475) BN 2
J 2
(-7738 3483);
DISPLAY 0.489362 (-7738 3483);
PAINT GREEN (-7738 3483);
FORCEPROP 2 LAST CDS_LIB mstr_standard
J 0
(-7800 3475);
DISPLAY 0.723404 (-7800 3475);
PAINT MONO (-7800 3475);
DISPLAY INVISIBLE (-7800 3475);
FORCEPROP 1 LAST BODY_TYPE PLUMBING
J 2
(-7800 3525);
DISPLAY 0.872340 (-7800 3525);
PAINT GREEN (-7800 3525);
DISPLAY INVISIBLE (-7800 3525);
FORCEPROP 1 LAST HDL_TAP TRUE
J 2
(-8125 3350);
DISPLAY 0.872340 (-8125 3350);
DISPLAY INVISIBLE (-8125 3350);
FORCEPROP 1 LAST PATH I15
J 2
(-7798 3475);
DISPLAY 0.872340 (-7798 3475);
PAINT GREEN (-7798 3475);
DISPLAY INVISIBLE (-7798 3475);
FORCEADD TAP..1
R 2
(-7800 3625);
FORCEPROP 3 LASTPIN (-7750 3625) SIG_NAME M_D_CPU1_SB_CB<5>
J 0
(-7740 3635);
DISPLAY 0.659574 (-7740 3635);
PAINT MONO (-7740 3635);
DISPLAY INVISIBLE (-7740 3635);
FORCEPROP 1 LASTPIN (-7750 3625) BN 5
J 2
(-7738 3633);
DISPLAY 0.489362 (-7738 3633);
PAINT GREEN (-7738 3633);
FORCEPROP 2 LAST CDS_LIB mstr_standard
J 0
(-7800 3625);
DISPLAY 0.723404 (-7800 3625);
PAINT MONO (-7800 3625);
DISPLAY INVISIBLE (-7800 3625);
FORCEPROP 1 LAST BODY_TYPE PLUMBING
J 2
(-7800 3675);
DISPLAY 0.872340 (-7800 3675);
PAINT GREEN (-7800 3675);
DISPLAY INVISIBLE (-7800 3675);
FORCEPROP 1 LAST HDL_TAP TRUE
J 2
(-8125 3500);
DISPLAY 0.872340 (-8125 3500);
DISPLAY INVISIBLE (-8125 3500);
FORCEPROP 1 LAST PATH I16
J 2
(-7798 3625);
DISPLAY 0.872340 (-7798 3625);
PAINT GREEN (-7798 3625);
DISPLAY INVISIBLE (-7798 3625);
FORCEADD SCONN288_DDR506112002KQ..3
(-1300 3750);
FORCEPROP 1 LAST LOCATION J30
J 0
(-1750 5725);
DISPLAY 0.468085 (-1750 5725);
PAINT SKYBLUE (-1750 5725);
FORCEPROP 0 LAST $SEC 3
J 0
(-1750 5875);
DISPLAY 0.680851 (-1750 5875);
PAINT MONO (-1750 5875);
DISPLAY INVISIBLE (-1750 5875);
FORCEPROP 2 LAST CDS_SEC 3
J 0
(-1750 5875);
DISPLAY 1.021277 (-1750 5875);
DISPLAY INVISIBLE (-1750 5875);
FORCEPROP 0 LASTPIN (-700 2150) $PN G1
J 0
(-690 2160);
DISPLAY 0.680851 (-690 2160);
PAINT MONO (-690 2160);
FORCEPROP 0 LASTPIN (-700 2100) $PN G2
J 0
(-690 2110);
DISPLAY 0.680851 (-690 2110);
PAINT MONO (-690 2110);
FORCEPROP 0 LASTPIN (-700 2050) $PN G3
J 0
(-690 2060);
DISPLAY 0.680851 (-690 2060);
PAINT MONO (-690 2060);
FORCEPROP 0 LASTPIN (-1900 5300) $PN 1
J 2
(-1910 5310);
DISPLAY 0.680851 (-1910 5310);
PAINT MONO (-1910 5310);
FORCEPROP 0 LASTPIN (-1900 5350) $PN 145
J 2
(-1910 5360);
DISPLAY 0.680851 (-1910 5360);
PAINT MONO (-1910 5360);
FORCEPROP 0 LASTPIN (-1900 5400) $PN 146
J 2
(-1910 5410);
DISPLAY 0.680851 (-1910 5410);
PAINT MONO (-1910 5410);
FORCEPROP 0 LASTPIN (-700 2250) $PN 6
J 0
(-690 2260);
DISPLAY 0.680851 (-690 2260);
PAINT MONO (-690 2260);
FORCEPROP 0 LASTPIN (-700 2300) $PN 8
J 0
(-690 2310);
DISPLAY 0.680851 (-690 2310);
PAINT MONO (-690 2310);
FORCEPROP 0 LASTPIN (-700 2350) $PN 10
J 0
(-690 2360);
DISPLAY 0.680851 (-690 2360);
PAINT MONO (-690 2360);
FORCEPROP 0 LASTPIN (-700 2400) $PN 13
J 0
(-690 2410);
DISPLAY 0.680851 (-690 2410);
PAINT MONO (-690 2410);
FORCEPROP 0 LASTPIN (-700 2450) $PN 15
J 0
(-690 2460);
DISPLAY 0.680851 (-690 2460);
PAINT MONO (-690 2460);
FORCEPROP 0 LASTPIN (-700 2500) $PN 17
J 0
(-690 2510);
DISPLAY 0.680851 (-690 2510);
PAINT MONO (-690 2510);
FORCEPROP 0 LASTPIN (-700 2550) $PN 19
J 0
(-690 2560);
DISPLAY 0.680851 (-690 2560);
PAINT MONO (-690 2560);
FORCEPROP 0 LASTPIN (-700 2600) $PN 21
J 0
(-690 2610);
DISPLAY 0.680851 (-690 2610);
PAINT MONO (-690 2610);
FORCEPROP 0 LASTPIN (-700 2650) $PN 24
J 0
(-690 2660);
DISPLAY 0.680851 (-690 2660);
PAINT MONO (-690 2660);
FORCEPROP 0 LASTPIN (-700 2700) $PN 26
J 0
(-690 2710);
DISPLAY 0.680851 (-690 2710);
PAINT MONO (-690 2710);
FORCEPROP 0 LASTPIN (-700 2750) $PN 28
J 0
(-690 2760);
DISPLAY 0.680851 (-690 2760);
PAINT MONO (-690 2760);
FORCEPROP 0 LASTPIN (-700 2800) $PN 30
J 0
(-690 2810);
DISPLAY 0.680851 (-690 2810);
PAINT MONO (-690 2810);
FORCEPROP 0 LASTPIN (-700 2850) $PN 32
J 0
(-690 2860);
DISPLAY 0.680851 (-690 2860);
PAINT MONO (-690 2860);
FORCEPROP 0 LASTPIN (-700 2900) $PN 35
J 0
(-690 2910);
DISPLAY 0.680851 (-690 2910);
PAINT MONO (-690 2910);
FORCEPROP 0 LASTPIN (-700 2950) $PN 37
J 0
(-690 2960);
DISPLAY 0.680851 (-690 2960);
PAINT MONO (-690 2960);
FORCEPROP 0 LASTPIN (-700 3000) $PN 39
J 0
(-690 3010);
DISPLAY 0.680851 (-690 3010);
PAINT MONO (-690 3010);
FORCEPROP 0 LASTPIN (-700 3050) $PN 41
J 0
(-690 3060);
DISPLAY 0.680851 (-690 3060);
PAINT MONO (-690 3060);
FORCEPROP 0 LASTPIN (-700 3100) $PN 43
J 0
(-690 3110);
DISPLAY 0.680851 (-690 3110);
PAINT MONO (-690 3110);
FORCEPROP 0 LASTPIN (-700 3150) $PN 46
J 0
(-690 3160);
DISPLAY 0.680851 (-690 3160);
PAINT MONO (-690 3160);
FORCEPROP 0 LASTPIN (-700 3200) $PN 48
J 0
(-690 3210);
DISPLAY 0.680851 (-690 3210);
PAINT MONO (-690 3210);
FORCEPROP 0 LASTPIN (-700 3250) $PN 50
J 0
(-690 3260);
DISPLAY 0.680851 (-690 3260);
PAINT MONO (-690 3260);
FORCEPROP 0 LASTPIN (-700 3300) $PN 52
J 0
(-690 3310);
DISPLAY 0.680851 (-690 3310);
PAINT MONO (-690 3310);
FORCEPROP 0 LASTPIN (-700 3350) $PN 54
J 0
(-690 3360);
DISPLAY 0.680851 (-690 3360);
PAINT MONO (-690 3360);
FORCEPROP 0 LASTPIN (-700 3400) $PN 57
J 0
(-690 3410);
DISPLAY 0.680851 (-690 3410);
PAINT MONO (-690 3410);
FORCEPROP 0 LASTPIN (-700 3450) $PN 59
J 0
(-690 3460);
DISPLAY 0.680851 (-690 3460);
PAINT MONO (-690 3460);
FORCEPROP 0 LASTPIN (-700 3500) $PN 61
J 0
(-690 3510);
DISPLAY 0.680851 (-690 3510);
PAINT MONO (-690 3510);
FORCEPROP 0 LASTPIN (-700 3550) $PN 63
J 0
(-690 3560);
DISPLAY 0.680851 (-690 3560);
PAINT MONO (-690 3560);
FORCEPROP 0 LASTPIN (-700 3600) $PN 65
J 0
(-690 3610);
DISPLAY 0.680851 (-690 3610);
PAINT MONO (-690 3610);
FORCEPROP 0 LASTPIN (-700 3650) $PN 67
J 0
(-690 3660);
DISPLAY 0.680851 (-690 3660);
PAINT MONO (-690 3660);
FORCEPROP 0 LASTPIN (-700 3700) $PN 69
J 0
(-690 3710);
DISPLAY 0.680851 (-690 3710);
PAINT MONO (-690 3710);
FORCEPROP 0 LASTPIN (-700 3750) $PN 71
J 0
(-690 3760);
DISPLAY 0.680851 (-690 3760);
PAINT MONO (-690 3760);
FORCEPROP 0 LASTPIN (-700 3800) $PN 73
J 0
(-690 3810);
DISPLAY 0.680851 (-690 3810);
PAINT MONO (-690 3810);
FORCEPROP 0 LASTPIN (-700 3850) $PN 75
J 0
(-690 3860);
DISPLAY 0.680851 (-690 3860);
PAINT MONO (-690 3860);
FORCEPROP 0 LASTPIN (-700 3900) $PN 77
J 0
(-690 3910);
DISPLAY 0.680851 (-690 3910);
PAINT MONO (-690 3910);
FORCEPROP 0 LASTPIN (-700 3950) $PN 79
J 0
(-690 3960);
DISPLAY 0.680851 (-690 3960);
PAINT MONO (-690 3960);
FORCEPROP 0 LASTPIN (-700 4000) $PN 81
J 0
(-690 4010);
DISPLAY 0.680851 (-690 4010);
PAINT MONO (-690 4010);
FORCEPROP 0 LASTPIN (-700 4050) $PN 83
J 0
(-690 4060);
DISPLAY 0.680851 (-690 4060);
PAINT MONO (-690 4060);
FORCEPROP 0 LASTPIN (-700 4100) $PN 85
J 0
(-690 4110);
DISPLAY 0.680851 (-690 4110);
PAINT MONO (-690 4110);
FORCEPROP 0 LASTPIN (-700 4150) $PN 88
J 0
(-690 4160);
DISPLAY 0.680851 (-690 4160);
PAINT MONO (-690 4160);
FORCEPROP 0 LASTPIN (-700 4200) $PN 90
J 0
(-690 4210);
DISPLAY 0.680851 (-690 4210);
PAINT MONO (-690 4210);
FORCEPROP 0 LASTPIN (-700 4250) $PN 92
J 0
(-690 4260);
DISPLAY 0.680851 (-690 4260);
PAINT MONO (-690 4260);
FORCEPROP 0 LASTPIN (-700 4300) $PN 95
J 0
(-690 4310);
DISPLAY 0.680851 (-690 4310);
PAINT MONO (-690 4310);
FORCEPROP 0 LASTPIN (-700 4350) $PN 97
J 0
(-690 4360);
DISPLAY 0.680851 (-690 4360);
PAINT MONO (-690 4360);
FORCEPROP 0 LASTPIN (-700 4400) $PN 99
J 0
(-690 4410);
DISPLAY 0.680851 (-690 4410);
PAINT MONO (-690 4410);
FORCEPROP 0 LASTPIN (-700 4450) $PN 101
J 0
(-690 4460);
DISPLAY 0.680851 (-690 4460);
PAINT MONO (-690 4460);
FORCEPROP 0 LASTPIN (-700 4500) $PN 103
J 0
(-690 4510);
DISPLAY 0.680851 (-690 4510);
PAINT MONO (-690 4510);
FORCEPROP 0 LASTPIN (-700 4550) $PN 106
J 0
(-690 4560);
DISPLAY 0.680851 (-690 4560);
PAINT MONO (-690 4560);
FORCEPROP 0 LASTPIN (-700 4600) $PN 108
J 0
(-690 4610);
DISPLAY 0.680851 (-690 4610);
PAINT MONO (-690 4610);
FORCEPROP 0 LASTPIN (-700 4650) $PN 110
J 0
(-690 4660);
DISPLAY 0.680851 (-690 4660);
PAINT MONO (-690 4660);
FORCEPROP 0 LASTPIN (-700 4700) $PN 112
J 0
(-690 4710);
DISPLAY 0.680851 (-690 4710);
PAINT MONO (-690 4710);
FORCEPROP 0 LASTPIN (-700 4750) $PN 114
J 0
(-690 4760);
DISPLAY 0.680851 (-690 4760);
PAINT MONO (-690 4760);
FORCEPROP 0 LASTPIN (-700 4800) $PN 117
J 0
(-690 4810);
DISPLAY 0.680851 (-690 4810);
PAINT MONO (-690 4810);
FORCEPROP 0 LASTPIN (-700 4850) $PN 119
J 0
(-690 4860);
DISPLAY 0.680851 (-690 4860);
PAINT MONO (-690 4860);
FORCEPROP 0 LASTPIN (-700 4900) $PN 121
J 0
(-690 4910);
DISPLAY 0.680851 (-690 4910);
PAINT MONO (-690 4910);
FORCEPROP 0 LASTPIN (-700 4950) $PN 123
J 0
(-690 4960);
DISPLAY 0.680851 (-690 4960);
PAINT MONO (-690 4960);
FORCEPROP 0 LASTPIN (-700 5000) $PN 125
J 0
(-690 5010);
DISPLAY 0.680851 (-690 5010);
PAINT MONO (-690 5010);
FORCEPROP 0 LASTPIN (-700 5050) $PN 128
J 0
(-690 5060);
DISPLAY 0.680851 (-690 5060);
PAINT MONO (-690 5060);
FORCEPROP 0 LASTPIN (-700 5100) $PN 130
J 0
(-690 5110);
DISPLAY 0.680851 (-690 5110);
PAINT MONO (-690 5110);
FORCEPROP 0 LASTPIN (-700 5150) $PN 132
J 0
(-690 5160);
DISPLAY 0.680851 (-690 5160);
PAINT MONO (-690 5160);
FORCEPROP 0 LASTPIN (-700 5200) $PN 134
J 0
(-690 5210);
DISPLAY 0.680851 (-690 5210);
PAINT MONO (-690 5210);
FORCEPROP 0 LASTPIN (-700 5250) $PN 136
J 0
(-690 5260);
DISPLAY 0.680851 (-690 5260);
PAINT MONO (-690 5260);
FORCEPROP 0 LASTPIN (-700 5300) $PN 139
J 0
(-690 5310);
DISPLAY 0.680851 (-690 5310);
PAINT MONO (-690 5310);
FORCEPROP 0 LASTPIN (-700 5350) $PN 141
J 0
(-690 5360);
DISPLAY 0.680851 (-690 5360);
PAINT MONO (-690 5360);
FORCEPROP 0 LASTPIN (-700 5400) $PN 143
J 0
(-690 5410);
DISPLAY 0.680851 (-690 5410);
PAINT MONO (-690 5410);
FORCEPROP 0 LASTPIN (-1900 2150) $PN 151
J 2
(-1910 2160);
DISPLAY 0.680851 (-1910 2160);
PAINT MONO (-1910 2160);
FORCEPROP 0 LASTPIN (-1900 2200) $PN 153
J 2
(-1910 2210);
DISPLAY 0.680851 (-1910 2210);
PAINT MONO (-1910 2210);
FORCEPROP 0 LASTPIN (-1900 2250) $PN 155
J 2
(-1910 2260);
DISPLAY 0.680851 (-1910 2260);
PAINT MONO (-1910 2260);
FORCEPROP 0 LASTPIN (-1900 2300) $PN 158
J 2
(-1910 2310);
DISPLAY 0.680851 (-1910 2310);
PAINT MONO (-1910 2310);
FORCEPROP 0 LASTPIN (-1900 2350) $PN 160
J 2
(-1910 2360);
DISPLAY 0.680851 (-1910 2360);
PAINT MONO (-1910 2360);
FORCEPROP 0 LASTPIN (-1900 2400) $PN 162
J 2
(-1910 2410);
DISPLAY 0.680851 (-1910 2410);
PAINT MONO (-1910 2410);
FORCEPROP 0 LASTPIN (-1900 2450) $PN 164
J 2
(-1910 2460);
DISPLAY 0.680851 (-1910 2460);
PAINT MONO (-1910 2460);
FORCEPROP 0 LASTPIN (-1900 2500) $PN 166
J 2
(-1910 2510);
DISPLAY 0.680851 (-1910 2510);
PAINT MONO (-1910 2510);
FORCEPROP 0 LASTPIN (-1900 2550) $PN 169
J 2
(-1910 2560);
DISPLAY 0.680851 (-1910 2560);
PAINT MONO (-1910 2560);
FORCEPROP 0 LASTPIN (-1900 2600) $PN 171
J 2
(-1910 2610);
DISPLAY 0.680851 (-1910 2610);
PAINT MONO (-1910 2610);
FORCEPROP 0 LASTPIN (-1900 2650) $PN 173
J 2
(-1910 2660);
DISPLAY 0.680851 (-1910 2660);
PAINT MONO (-1910 2660);
FORCEPROP 0 LASTPIN (-1900 2700) $PN 175
J 2
(-1910 2710);
DISPLAY 0.680851 (-1910 2710);
PAINT MONO (-1910 2710);
FORCEPROP 0 LASTPIN (-1900 2750) $PN 177
J 2
(-1910 2760);
DISPLAY 0.680851 (-1910 2760);
PAINT MONO (-1910 2760);
FORCEPROP 0 LASTPIN (-1900 2800) $PN 180
J 2
(-1910 2810);
DISPLAY 0.680851 (-1910 2810);
PAINT MONO (-1910 2810);
FORCEPROP 0 LASTPIN (-1900 2850) $PN 182
J 2
(-1910 2860);
DISPLAY 0.680851 (-1910 2860);
PAINT MONO (-1910 2860);
FORCEPROP 0 LASTPIN (-1900 2900) $PN 184
J 2
(-1910 2910);
DISPLAY 0.680851 (-1910 2910);
PAINT MONO (-1910 2910);
FORCEPROP 0 LASTPIN (-1900 2950) $PN 186
J 2
(-1910 2960);
DISPLAY 0.680851 (-1910 2960);
PAINT MONO (-1910 2960);
FORCEPROP 0 LASTPIN (-1900 3000) $PN 188
J 2
(-1910 3010);
DISPLAY 0.680851 (-1910 3010);
PAINT MONO (-1910 3010);
FORCEPROP 0 LASTPIN (-1900 3050) $PN 191
J 2
(-1910 3060);
DISPLAY 0.680851 (-1910 3060);
PAINT MONO (-1910 3060);
FORCEPROP 0 LASTPIN (-1900 3100) $PN 193
J 2
(-1910 3110);
DISPLAY 0.680851 (-1910 3110);
PAINT MONO (-1910 3110);
FORCEPROP 0 LASTPIN (-1900 3150) $PN 195
J 2
(-1910 3160);
DISPLAY 0.680851 (-1910 3160);
PAINT MONO (-1910 3160);
FORCEPROP 0 LASTPIN (-1900 3200) $PN 197
J 2
(-1910 3210);
DISPLAY 0.680851 (-1910 3210);
PAINT MONO (-1910 3210);
FORCEPROP 0 LASTPIN (-1900 3250) $PN 199
J 2
(-1910 3260);
DISPLAY 0.680851 (-1910 3260);
PAINT MONO (-1910 3260);
FORCEPROP 0 LASTPIN (-1900 3300) $PN 202
J 2
(-1910 3310);
DISPLAY 0.680851 (-1910 3310);
PAINT MONO (-1910 3310);
FORCEPROP 0 LASTPIN (-1900 3350) $PN 204
J 2
(-1910 3360);
DISPLAY 0.680851 (-1910 3360);
PAINT MONO (-1910 3360);
FORCEPROP 0 LASTPIN (-1900 3400) $PN 206
J 2
(-1910 3410);
DISPLAY 0.680851 (-1910 3410);
PAINT MONO (-1910 3410);
FORCEPROP 0 LASTPIN (-1900 3450) $PN 208
J 2
(-1910 3460);
DISPLAY 0.680851 (-1910 3460);
PAINT MONO (-1910 3460);
FORCEPROP 0 LASTPIN (-1900 3500) $PN 210
J 2
(-1910 3510);
DISPLAY 0.680851 (-1910 3510);
PAINT MONO (-1910 3510);
FORCEPROP 0 LASTPIN (-1900 3550) $PN 212
J 2
(-1910 3560);
DISPLAY 0.680851 (-1910 3560);
PAINT MONO (-1910 3560);
FORCEPROP 0 LASTPIN (-1900 3600) $PN 214
J 2
(-1910 3610);
DISPLAY 0.680851 (-1910 3610);
PAINT MONO (-1910 3610);
FORCEPROP 0 LASTPIN (-1900 3650) $PN 216
J 2
(-1910 3660);
DISPLAY 0.680851 (-1910 3660);
PAINT MONO (-1910 3660);
FORCEPROP 0 LASTPIN (-1900 3700) $PN 219
J 2
(-1910 3710);
DISPLAY 0.680851 (-1910 3710);
PAINT MONO (-1910 3710);
FORCEPROP 0 LASTPIN (-1900 3750) $PN 222
J 2
(-1910 3760);
DISPLAY 0.680851 (-1910 3760);
PAINT MONO (-1910 3760);
FORCEPROP 0 LASTPIN (-1900 3800) $PN 224
J 2
(-1910 3810);
DISPLAY 0.680851 (-1910 3810);
PAINT MONO (-1910 3810);
FORCEPROP 0 LASTPIN (-1900 3850) $PN 226
J 2
(-1910 3860);
DISPLAY 0.680851 (-1910 3860);
PAINT MONO (-1910 3860);
FORCEPROP 0 LASTPIN (-1900 3900) $PN 228
J 2
(-1910 3910);
DISPLAY 0.680851 (-1910 3910);
PAINT MONO (-1910 3910);
FORCEPROP 0 LASTPIN (-1900 3950) $PN 230
J 2
(-1910 3960);
DISPLAY 0.680851 (-1910 3960);
PAINT MONO (-1910 3960);
FORCEPROP 0 LASTPIN (-1900 4000) $PN 233
J 2
(-1910 4010);
DISPLAY 0.680851 (-1910 4010);
PAINT MONO (-1910 4010);
FORCEPROP 0 LASTPIN (-1900 4050) $PN 235
J 2
(-1910 4060);
DISPLAY 0.680851 (-1910 4060);
PAINT MONO (-1910 4060);
FORCEPROP 0 LASTPIN (-1900 4100) $PN 237
J 2
(-1910 4110);
DISPLAY 0.680851 (-1910 4110);
PAINT MONO (-1910 4110);
FORCEPROP 0 LASTPIN (-1900 4150) $PN 240
J 2
(-1910 4160);
DISPLAY 0.680851 (-1910 4160);
PAINT MONO (-1910 4160);
FORCEPROP 0 LASTPIN (-1900 4200) $PN 242
J 2
(-1910 4210);
DISPLAY 0.680851 (-1910 4210);
PAINT MONO (-1910 4210);
FORCEPROP 0 LASTPIN (-1900 4250) $PN 244
J 2
(-1910 4260);
DISPLAY 0.680851 (-1910 4260);
PAINT MONO (-1910 4260);
FORCEPROP 0 LASTPIN (-1900 4300) $PN 246
J 2
(-1910 4310);
DISPLAY 0.680851 (-1910 4310);
PAINT MONO (-1910 4310);
FORCEPROP 0 LASTPIN (-1900 4350) $PN 248
J 2
(-1910 4360);
DISPLAY 0.680851 (-1910 4360);
PAINT MONO (-1910 4360);
FORCEPROP 0 LASTPIN (-1900 4400) $PN 251
J 2
(-1910 4410);
DISPLAY 0.680851 (-1910 4410);
PAINT MONO (-1910 4410);
FORCEPROP 0 LASTPIN (-1900 4450) $PN 253
J 2
(-1910 4460);
DISPLAY 0.680851 (-1910 4460);
PAINT MONO (-1910 4460);
FORCEPROP 0 LASTPIN (-1900 4500) $PN 255
J 2
(-1910 4510);
DISPLAY 0.680851 (-1910 4510);
PAINT MONO (-1910 4510);
FORCEPROP 0 LASTPIN (-1900 4550) $PN 257
J 2
(-1910 4560);
DISPLAY 0.680851 (-1910 4560);
PAINT MONO (-1910 4560);
FORCEPROP 0 LASTPIN (-1900 4600) $PN 259
J 2
(-1910 4610);
DISPLAY 0.680851 (-1910 4610);
PAINT MONO (-1910 4610);
FORCEPROP 0 LASTPIN (-1900 4650) $PN 262
J 2
(-1910 4660);
DISPLAY 0.680851 (-1910 4660);
PAINT MONO (-1910 4660);
FORCEPROP 0 LASTPIN (-1900 4700) $PN 264
J 2
(-1910 4710);
DISPLAY 0.680851 (-1910 4710);
PAINT MONO (-1910 4710);
FORCEPROP 0 LASTPIN (-1900 4750) $PN 266
J 2
(-1910 4760);
DISPLAY 0.680851 (-1910 4760);
PAINT MONO (-1910 4760);
FORCEPROP 0 LASTPIN (-1900 4800) $PN 268
J 2
(-1910 4810);
DISPLAY 0.680851 (-1910 4810);
PAINT MONO (-1910 4810);
FORCEPROP 0 LASTPIN (-1900 4850) $PN 270
J 2
(-1910 4860);
DISPLAY 0.680851 (-1910 4860);
PAINT MONO (-1910 4860);
FORCEPROP 0 LASTPIN (-1900 4900) $PN 273
J 2
(-1910 4910);
DISPLAY 0.680851 (-1910 4910);
PAINT MONO (-1910 4910);
FORCEPROP 0 LASTPIN (-1900 4950) $PN 275
J 2
(-1910 4960);
DISPLAY 0.680851 (-1910 4960);
PAINT MONO (-1910 4960);
FORCEPROP 0 LASTPIN (-1900 5000) $PN 277
J 2
(-1910 5010);
DISPLAY 0.680851 (-1910 5010);
PAINT MONO (-1910 5010);
FORCEPROP 0 LASTPIN (-1900 5050) $PN 279
J 2
(-1910 5060);
DISPLAY 0.680851 (-1910 5060);
PAINT MONO (-1910 5060);
FORCEPROP 0 LASTPIN (-1900 5100) $PN 281
J 2
(-1910 5110);
DISPLAY 0.680851 (-1910 5110);
PAINT MONO (-1910 5110);
FORCEPROP 0 LASTPIN (-1900 5150) $PN 284
J 2
(-1910 5160);
DISPLAY 0.680851 (-1910 5160);
PAINT MONO (-1910 5160);
FORCEPROP 0 LASTPIN (-1900 5200) $PN 286
J 2
(-1910 5210);
DISPLAY 0.680851 (-1910 5210);
PAINT MONO (-1910 5210);
FORCEPROP 0 LASTPIN (-1900 5250) $PN 288
J 2
(-1910 5260);
DISPLAY 0.680851 (-1910 5260);
PAINT MONO (-1910 5260);
FORCEPROP 2 LAST VALUE SCONN288_DDR506112002KQ
J 0
(-1750 5775);
DISPLAY 0.489362 (-1750 5775);
PAINT SKYBLUE (-1750 5775);
FORCEPROP 1 LAST MATERIAL IO
J 0
(-1750 5575);
DISPLAY 0.468085 (-1750 5575);
PAINT SKYBLUE (-1750 5575);
FORCEPROP 2 LAST PART_TYPE SMLF
J 0
(-1750 5825);
DISPLAY 1.021277 (-1750 5825);
FORCEPROP 2 LAST CDS_LIB pure_quanta
J 0
(-1300 3750);
DISPLAY INVISIBLE (-1300 3750);
FORCEPROP 1 LAST NEEDS_NO_SIZE TRUE
J 0
(-1300 3750);
DISPLAY 0.723404 (-1300 3750);
PAINT GREEN (-1300 3750);
DISPLAY INVISIBLE (-1300 3750);
FORCEPROP 1 LAST CDS_LMAN_SYM_OUTLINE -450,1800,450,-1750
J 0
(-1300 3750);
DISPLAY 0.468085 (-1300 3750);
PAINT GREEN (-1300 3750);
DISPLAY INVISIBLE (-1300 3750);
FORCEPROP 1 LAST PATH I161
J 0
(-1300 3750);
DISPLAY 0.723404 (-1300 3750);
PAINT GREEN (-1300 3750);
DISPLAY INVISIBLE (-1300 3750);
FORCEPROP 1 LAST PART_NUMBER DFHST8FS479
J 0
(-1750 5650);
DISPLAY 0.468085 (-1750 5650);
PAINT SKYBLUE (-1750 5650);
DISPLAY INVISIBLE (-1750 5650);
FORCEADD GND..1
(-400 1800);
FORCEPROP 3 LASTPIN (-400 1850) SIG_NAME GND\g
J 0
(-390 1860);
DISPLAY 0.659574 (-390 1860);
PAINT MONO (-390 1860);
DISPLAY INVISIBLE (-390 1860);
FORCEPROP 1 LAST VOLTAGE 0.0
J 0
(-445 1757);
DISPLAY 0.723404 (-445 1757);
PAINT SKYBLUE (-445 1757);
DISPLAY INVISIBLE (-445 1757);
FORCEPROP 2 LAST CDS_LIB mstr_symbols
J 0
(-400 1800);
DISPLAY 0.723404 (-400 1800);
DISPLAY INVISIBLE (-400 1800);
FORCEPROP 1 LAST SIZE 1B
J 0
(-325 1750);
DISPLAY 0.851064 (-325 1750);
PAINT GREEN (-325 1750);
DISPLAY INVISIBLE (-325 1750);
FORCEPROP 1 LAST BODY_TYPE PLUMBING
J 0
(-445 1757);
DISPLAY 0.340426 (-445 1757);
PAINT GREEN (-445 1757);
DISPLAY INVISIBLE (-445 1757);
FORCEPROP 1 LAST HDL_POWER GND
J 0
(-400 1950);
DISPLAY 0.851064 (-400 1950);
PAINT GREEN (-400 1950);
DISPLAY INVISIBLE (-400 1950);
FORCEPROP 1 LAST PATH I162
J 0
(-325 1800);
DISPLAY 0.872340 (-325 1800);
PAINT AQUA (-325 1800);
DISPLAY INVISIBLE (-325 1800);
FORCEADD TAP..1
R 2
(-7800 3575);
FORCEPROP 3 LASTPIN (-7750 3575) SIG_NAME M_D_CPU1_SB_CB<4>
J 0
(-7740 3585);
DISPLAY 0.659574 (-7740 3585);
PAINT MONO (-7740 3585);
DISPLAY INVISIBLE (-7740 3585);
FORCEPROP 1 LASTPIN (-7750 3575) BN 4
J 2
(-7738 3583);
DISPLAY 0.489362 (-7738 3583);
PAINT GREEN (-7738 3583);
FORCEPROP 2 LAST CDS_LIB mstr_standard
J 0
(-7800 3575);
DISPLAY 0.723404 (-7800 3575);
PAINT MONO (-7800 3575);
DISPLAY INVISIBLE (-7800 3575);
FORCEPROP 1 LAST BODY_TYPE PLUMBING
J 2
(-7800 3625);
DISPLAY 0.872340 (-7800 3625);
PAINT GREEN (-7800 3625);
DISPLAY INVISIBLE (-7800 3625);
FORCEPROP 1 LAST HDL_TAP TRUE
J 2
(-8125 3450);
DISPLAY 0.872340 (-8125 3450);
DISPLAY INVISIBLE (-8125 3450);
FORCEPROP 1 LAST PATH I17
J 2
(-7798 3575);
DISPLAY 0.872340 (-7798 3575);
PAINT GREEN (-7798 3575);
DISPLAY INVISIBLE (-7798 3575);
FORCEADD TAP..1
R 2
(-7800 3675);
FORCEPROP 3 LASTPIN (-7750 3675) SIG_NAME M_D_CPU1_SB_CB<6>
J 0
(-7740 3685);
DISPLAY 0.659574 (-7740 3685);
PAINT MONO (-7740 3685);
DISPLAY INVISIBLE (-7740 3685);
FORCEPROP 1 LASTPIN (-7750 3675) BN 6
J 2
(-7738 3683);
DISPLAY 0.489362 (-7738 3683);
PAINT GREEN (-7738 3683);
FORCEPROP 2 LAST CDS_LIB mstr_standard
J 0
(-7800 3675);
DISPLAY 0.723404 (-7800 3675);
PAINT MONO (-7800 3675);
DISPLAY INVISIBLE (-7800 3675);
FORCEPROP 1 LAST BODY_TYPE PLUMBING
J 2
(-7800 3725);
DISPLAY 0.872340 (-7800 3725);
PAINT GREEN (-7800 3725);
DISPLAY INVISIBLE (-7800 3725);
FORCEPROP 1 LAST HDL_TAP TRUE
J 2
(-8125 3550);
DISPLAY 0.872340 (-8125 3550);
DISPLAY INVISIBLE (-8125 3550);
FORCEPROP 1 LAST PATH I18
J 2
(-7798 3675);
DISPLAY 0.872340 (-7798 3675);
PAINT GREEN (-7798 3675);
DISPLAY INVISIBLE (-7798 3675);
FORCEADD Q_CAP..1
R 2
(-8750 3400);
FORCEPROP 1 LAST LOCATION C148
J 2
(-8800 3500);
DISPLAY 0.489362 (-8800 3500);
PAINT SKYBLUE (-8800 3500);
FORCEPROP 0 LAST $SEC 1
J 0
(-8800 3550);
DISPLAY 0.680851 (-8800 3550);
PAINT MONO (-8800 3550);
DISPLAY INVISIBLE (-8800 3550);
FORCEPROP 0 LAST CDS_SEC 1
J 0
(-8800 3550);
DISPLAY 1.021277 (-8800 3550);
DISPLAY INVISIBLE (-8800 3550);
FORCEPROP 1 LASTPIN (-8750 3500) $PN 1
J 2
(-8760 3480);
DISPLAY 0.489362 (-8760 3480);
PAINT MONO (-8760 3480);
FORCEPROP 1 LASTPIN (-8750 3300) $PN 2
J 2
(-8760 3280);
DISPLAY 0.489362 (-8760 3280);
PAINT MONO (-8760 3280);
FORCEPROP 1 LAST TOLERANCE 10%
J 2
(-8800 3350);
DISPLAY 0.489362 (-8800 3350);
PAINT SKYBLUE (-8800 3350);
FORCEPROP 1 LAST MATERIAL X7R
J 2
(-8800 3300);
DISPLAY 0.489362 (-8800 3300);
PAINT SKYBLUE (-8800 3300);
FORCEPROP 1 LAST VOLTAGE 25V
J 2
(-8800 3400);
DISPLAY 0.489362 (-8800 3400);
PAINT SKYBLUE (-8800 3400);
FORCEPROP 1 LAST VALUE 0.1UF
J 2
(-8800 3450);
DISPLAY 0.489362 (-8800 3450);
PAINT SKYBLUE (-8800 3450);
FORCEPROP 1 LAST PACK_TYPE 0402
J 2
(-8800 3200);
DISPLAY 0.489362 (-8800 3200);
PAINT SKYBLUE (-8800 3200);
FORCEPROP 2 LAST CDS_LIB pure_quanta
J 0
(-8750 3400);
DISPLAY INVISIBLE (-8750 3400);
FORCEPROP 0 LAST BOM_COST MEM
J 2
(-8805 3545);
DISPLAY 0.595745 (-8805 3545);
PAINT MONO (-8805 3545);
DISPLAY INVISIBLE (-8805 3545);
FORCEPROP 2 LAST ROOM 
J 2
(-8805 3545);
DISPLAY 0.595745 (-8805 3545);
PAINT RED (-8805 3545);
DISPLAY INVISIBLE (-8805 3545);
FORCEPROP 1 LAST PATH I185
J 2
(-8800 3550);
DISPLAY 0.978723 (-8800 3550);
PAINT WHITE (-8800 3550);
DISPLAY INVISIBLE (-8800 3550);
FORCEPROP 1 LAST PART_NUMBER CH4104K1B00
J 2
(-8800 3250);
DISPLAY 0.489362 (-8800 3250);
PAINT SKYBLUE (-8800 3250);
DISPLAY INVISIBLE (-8800 3250);
FORCEADD GND..1
(-8750 3175);
FORCEPROP 3 LASTPIN (-8750 3225) SIG_NAME GND\g
J 0
(-8740 3235);
DISPLAY 0.659574 (-8740 3235);
PAINT MONO (-8740 3235);
DISPLAY INVISIBLE (-8740 3235);
FORCEPROP 2 LAST ROOM MEM_EFGH_DECOUPLING_CAPS
J 0
(-8725 3250);
DISPLAY 0.659574 (-8725 3250);
PAINT RED (-8725 3250);
DISPLAY INVISIBLE (-8725 3250);
FORCEPROP 1 LAST VOLTAGE 0
J 0
(-8770 3270);
DISPLAY 0.829787 (-8770 3270);
PAINT SKYBLUE (-8770 3270);
DISPLAY INVISIBLE (-8770 3270);
FORCEPROP 2 LAST BOM_COST MEM
J 0
(-8725 3300);
DISPLAY 0.659574 (-8725 3300);
DISPLAY INVISIBLE (-8725 3300);
FORCEPROP 1 LAST SIZE 1B
J 0
(-8675 3125);
DISPLAY 0.723404 (-8675 3125);
PAINT GREEN (-8675 3125);
DISPLAY INVISIBLE (-8675 3125);
FORCEPROP 2 LAST CDS_LIB mstr_symbols
J 0
(-8750 3175);
DISPLAY 0.808511 (-8750 3175);
DISPLAY INVISIBLE (-8750 3175);
FORCEPROP 1 LAST BODY_TYPE PLUMBING
J 0
(-8795 3132);
DISPLAY 0.276596 (-8795 3132);
PAINT GREEN (-8795 3132);
DISPLAY INVISIBLE (-8795 3132);
FORCEPROP 1 LAST HDL_POWER GND
J 0
(-8750 3325);
DISPLAY 0.723404 (-8750 3325);
PAINT GREEN (-8750 3325);
DISPLAY INVISIBLE (-8750 3325);
FORCEPROP 1 LAST PATH I186
J 0
(-8675 3175);
DISPLAY 0.872340 (-8675 3175);
PAINT AQUA (-8675 3175);
DISPLAY INVISIBLE (-8675 3175);
FORCEADD OFFPAGE..6
(-9100 2325);
FORCEPROP 2 LAST $XR4 103 
J 0
(-9439 2253);
DISPLAY 0.638298 (-9439 2253);
PAINT MONO (-9439 2253);
FORCEPROP 2 LAST $XR3 102 
J 0
(-9349 2361);
DISPLAY 0.638298 (-9349 2361);
PAINT MONO (-9349 2361);
FORCEPROP 2 LAST $XR2 100 
J 0
(-9439 2289);
DISPLAY 0.638298 (-9439 2289);
PAINT MONO (-9439 2289);
FORCEPROP 2 LAST $XR1 99 
J 0
(-9439 2325);
DISPLAY 0.638298 (-9439 2325);
PAINT MONO (-9439 2325);
FORCEPROP 2 LAST $XR0 98 
J 0
(-9349 2325);
DISPLAY 0.638298 (-9349 2325);
PAINT MONO (-9349 2325);
FORCEPROP 2 LAST CDS_LIB mstr_standard
J 0
(-9100 2325);
DISPLAY 0.808511 (-9100 2325);
DISPLAY INVISIBLE (-9100 2325);
FORCEPROP 1 LAST OFFPAGE TRUE
J 0
(-8775 2200);
DISPLAY 0.872340 (-8775 2200);
PAINT GREEN (-8775 2200);
DISPLAY INVISIBLE (-8775 2200);
FORCEPROP 1 LAST COMMENT_BODY TRUE
J 0
(-9000 2250);
DISPLAY 0.872340 (-9000 2250);
PAINT GREEN (-9000 2250);
DISPLAY INVISIBLE (-9000 2250);
FORCEPROP 2 LAST PATH I187
J 0
(-9050 2400);
DISPLAY 1.021277 (-9050 2400);
DISPLAY INVISIBLE (-9050 2400);
FORCEADD Q_RES..1
R 2
(-8600 2325);
FORCEPROP 1 LAST LOCATION R306
J 2
(-8575 2350);
DISPLAY 0.489362 (-8575 2350);
PAINT SKYBLUE (-8575 2350);
FORCEPROP 0 LAST $SEC 1
J 0
(-8575 2400);
DISPLAY 0.680851 (-8575 2400);
PAINT MONO (-8575 2400);
DISPLAY INVISIBLE (-8575 2400);
FORCEPROP 0 LAST CDS_SEC 1
J 0
(-8575 2400);
DISPLAY 1.021277 (-8575 2400);
DISPLAY INVISIBLE (-8575 2400);
FORCEPROP 1 LASTPIN (-8500 2325) $PN 1
J 2
(-8512 2337);
DISPLAY 0.489362 (-8512 2337);
PAINT MONO (-8512 2337);
FORCEPROP 1 LASTPIN (-8700 2325) $PN 2
J 2
(-8662 2337);
DISPLAY 0.489362 (-8662 2337);
PAINT MONO (-8662 2337);
FORCEPROP 1 LAST VALUE 1K
J 0
(-8600 2275);
DISPLAY 0.489362 (-8600 2275);
PAINT SKYBLUE (-8600 2275);
FORCEPROP 1 LAST PACK_TYPE 0402LF
J 0
(-8775 2250);
DISPLAY 0.489362 (-8775 2250);
PAINT SKYBLUE (-8775 2250);
DISPLAY INVISIBLE (-8775 2250);
FORCEPROP 1 LAST MATERIAL CHIP
J 0
(-8775 2300);
DISPLAY 0.489362 (-8775 2300);
PAINT SKYBLUE (-8775 2300);
DISPLAY INVISIBLE (-8775 2300);
FORCEPROP 1 LAST WATTAGE 1/16W
J 0
(-8525 2250);
DISPLAY 0.489362 (-8525 2250);
PAINT SKYBLUE (-8525 2250);
DISPLAY INVISIBLE (-8525 2250);
FORCEPROP 2 LAST BOM_COST MEM
J 0
(-8625 2475);
DISPLAY 0.744681 (-8625 2475);
PAINT WHITE (-8625 2475);
DISPLAY INVISIBLE (-8625 2475);
FORCEPROP 2 LAST CDS_LIB pure_quanta
J 0
(-8600 2325);
DISPLAY INVISIBLE (-8600 2325);
FORCEPROP 1 LAST TOLERANCE 1%
J 2
(-8475 2300);
DISPLAY 0.489362 (-8475 2300);
PAINT SKYBLUE (-8475 2300);
DISPLAY INVISIBLE (-8475 2300);
FORCEPROP 2 LAST ROOM 
J 0
(-8625 2425);
DISPLAY 0.744681 (-8625 2425);
PAINT RED (-8625 2425);
DISPLAY INVISIBLE (-8625 2425);
FORCEPROP 1 LAST PATH I188
J 2
(-8550 2475);
DISPLAY 0.978723 (-8550 2475);
PAINT WHITE (-8550 2475);
DISPLAY INVISIBLE (-8550 2475);
FORCEPROP 1 LAST PART_NUMBER CS21002FB06
J 0
(-8700 2375);
DISPLAY 0.489362 (-8700 2375);
PAINT SKYBLUE (-8700 2375);
DISPLAY INVISIBLE (-8700 2375);
FORCEADD VCC_CORE..1
(-8475 2650);
FORCEPROP 3 LASTPIN (-8475 2600) SIG_NAME P3V3\g
J 0
(-8465 2610);
DISPLAY 0.659574 (-8465 2610);
PAINT MONO (-8465 2610);
DISPLAY INVISIBLE (-8465 2610);
FORCEPROP 1 LAST HDL_POWER P3V3
J 1
(-8475 2700);
DISPLAY 0.489362 (-8475 2700);
PAINT GREEN (-8475 2700);
FORCEPROP 2 LAST ROOM PVCCINFAON_CPU0_CTRL
J 0
(-8475 2750);
DISPLAY 0.808511 (-8475 2750);
PAINT RED (-8475 2750);
DISPLAY INVISIBLE (-8475 2750);
FORCEPROP 0 LAST VOLTAGE 3.3
J 0
(-8750 2800);
DISPLAY 1.021277 (-8750 2800);
PAINT SKYBLUE (-8750 2800);
DISPLAY INVISIBLE (-8750 2800);
FORCEPROP 2 LAST CDS_LIB mstr_symbols
J 0
(-8475 2650);
DISPLAY INVISIBLE (-8475 2650);
FORCEPROP 1 LAST PATH I189
J 0
(-8425 2675);
DISPLAY 0.872340 (-8425 2675);
PAINT AQUA (-8425 2675);
DISPLAY INVISIBLE (-8425 2675);
FORCEADD TAP..1
R 2
(-7800 3875);
FORCEPROP 3 LASTPIN (-7750 3875) SIG_NAME M_D_CPU1_SA_CB<1>
J 0
(-7740 3885);
DISPLAY 0.659574 (-7740 3885);
PAINT MONO (-7740 3885);
DISPLAY INVISIBLE (-7740 3885);
FORCEPROP 1 LASTPIN (-7750 3875) BN 1
J 2
(-7738 3883);
DISPLAY 0.489362 (-7738 3883);
PAINT GREEN (-7738 3883);
FORCEPROP 2 LAST CDS_LIB mstr_standard
J 0
(-7800 3875);
DISPLAY 0.723404 (-7800 3875);
PAINT MONO (-7800 3875);
DISPLAY INVISIBLE (-7800 3875);
FORCEPROP 1 LAST BODY_TYPE PLUMBING
J 2
(-7800 3925);
DISPLAY 0.872340 (-7800 3925);
PAINT GREEN (-7800 3925);
DISPLAY INVISIBLE (-7800 3925);
FORCEPROP 1 LAST HDL_TAP TRUE
J 2
(-8125 3750);
DISPLAY 0.872340 (-8125 3750);
DISPLAY INVISIBLE (-8125 3750);
FORCEPROP 1 LAST PATH I19
J 2
(-7798 3875);
DISPLAY 0.872340 (-7798 3875);
PAINT GREEN (-7798 3875);
DISPLAY INVISIBLE (-7798 3875);
FORCEADD Q_RES..2
(-8475 2475);
FORCEPROP 1 LAST LOCATION R106
J 0
(-8430 2600);
DISPLAY 0.489362 (-8430 2600);
PAINT SKYBLUE (-8430 2600);
FORCEPROP 0 LAST $SEC 1
J 0
(-8425 2650);
DISPLAY 0.680851 (-8425 2650);
PAINT MONO (-8425 2650);
DISPLAY INVISIBLE (-8425 2650);
FORCEPROP 0 LAST CDS_SEC 1
J 0
(-8425 2650);
DISPLAY 1.021277 (-8425 2650);
DISPLAY INVISIBLE (-8425 2650);
FORCEPROP 1 LASTPIN (-8475 2575) $PN 1
J 0
(-8470 2537);
DISPLAY 0.489362 (-8470 2537);
PAINT MONO (-8470 2537);
FORCEPROP 1 LASTPIN (-8475 2375) $PN 2
J 0
(-8470 2385);
DISPLAY 0.489362 (-8470 2385);
PAINT MONO (-8470 2385);
FORCEPROP 1 LAST WATTAGE 1/16W
J 0
(-8425 2500);
DISPLAY 0.489362 (-8425 2500);
PAINT SKYBLUE (-8425 2500);
FORCEPROP 1 LAST MATERIAL EMPTY
J 0
(-8425 2475);
DISPLAY 0.489362 (-8425 2475);
PAINT RED (-8425 2475);
FORCEPROP 1 LAST PACK_TYPE 0402LF
J 0
(-8425 2425);
DISPLAY 0.489362 (-8425 2425);
PAINT SKYBLUE (-8425 2425);
FORCEPROP 1 LAST VALUE 1K
J 0
(-8430 2550);
DISPLAY 0.489362 (-8430 2550);
PAINT SKYBLUE (-8430 2550);
FORCEPROP 1 LAST TOLERANCE 1%
J 0
(-8425 2525);
DISPLAY 0.489362 (-8425 2525);
PAINT SKYBLUE (-8425 2525);
FORCEPROP 2 LAST CDS_LIB pure_quanta
J 2
(-8475 2475);
DISPLAY INVISIBLE (-8475 2475);
FORCEPROP 2 LAST BOM_COST MEM
J 0
(-8425 2650);
DISPLAY 0.808511 (-8425 2650);
DISPLAY INVISIBLE (-8425 2650);
FORCEPROP 2 LAST ROOM 
J 0
(-8425 2700);
DISPLAY 0.808511 (-8425 2700);
PAINT RED (-8425 2700);
DISPLAY INVISIBLE (-8425 2700);
FORCEPROP 1 LAST PATH I190
J 0
(-8425 2650);
DISPLAY 0.978723 (-8425 2650);
PAINT WHITE (-8425 2650);
DISPLAY INVISIBLE (-8425 2650);
FORCEPROP 1 LAST PART_NUMBER CS21002FB06
J 0
(-8425 2450);
DISPLAY 0.489362 (-8425 2450);
PAINT SKYBLUE (-8425 2450);
DISPLAY INVISIBLE (-8425 2450);
FORCEADD TAP..1
(-3275 3875);
FORCEPROP 3 LASTPIN (-3325 3875) SIG_NAME M_D_CPU1_SA_DQS_DN<1>
J 0
(-3315 3885);
DISPLAY 0.659574 (-3315 3885);
PAINT MONO (-3315 3885);
DISPLAY INVISIBLE (-3315 3885);
FORCEPROP 1 LASTPIN (-3325 3875) BN 1
J 0
(-3337 3883);
DISPLAY 0.489362 (-3337 3883);
PAINT GREEN (-3337 3883);
FORCEPROP 2 LAST CDS_LIB mstr_standard
J 0
(-3275 3875);
DISPLAY 0.723404 (-3275 3875);
PAINT MONO (-3275 3875);
DISPLAY INVISIBLE (-3275 3875);
FORCEPROP 1 LAST BODY_TYPE PLUMBING
J 0
(-3275 3925);
DISPLAY 0.872340 (-3275 3925);
PAINT GREEN (-3275 3925);
DISPLAY INVISIBLE (-3275 3925);
FORCEPROP 1 LAST HDL_TAP TRUE
J 0
(-2950 3750);
DISPLAY 0.872340 (-2950 3750);
DISPLAY INVISIBLE (-2950 3750);
FORCEPROP 1 LAST PATH I191
J 0
(-3277 3875);
DISPLAY 0.872340 (-3277 3875);
PAINT GREEN (-3277 3875);
DISPLAY INVISIBLE (-3277 3875);
FORCEADD TAP..1
(-3275 3975);
FORCEPROP 3 LASTPIN (-3325 3975) SIG_NAME M_D_CPU1_SA_DQS_DN<2>
J 0
(-3315 3985);
DISPLAY 0.659574 (-3315 3985);
PAINT MONO (-3315 3985);
DISPLAY INVISIBLE (-3315 3985);
FORCEPROP 1 LASTPIN (-3325 3975) BN 2
J 0
(-3337 3983);
DISPLAY 0.489362 (-3337 3983);
PAINT GREEN (-3337 3983);
FORCEPROP 2 LAST CDS_LIB mstr_standard
J 0
(-3275 3975);
DISPLAY 0.723404 (-3275 3975);
PAINT MONO (-3275 3975);
DISPLAY INVISIBLE (-3275 3975);
FORCEPROP 1 LAST BODY_TYPE PLUMBING
J 0
(-3275 4025);
DISPLAY 0.872340 (-3275 4025);
PAINT GREEN (-3275 4025);
DISPLAY INVISIBLE (-3275 4025);
FORCEPROP 1 LAST HDL_TAP TRUE
J 0
(-2950 3850);
DISPLAY 0.872340 (-2950 3850);
DISPLAY INVISIBLE (-2950 3850);
FORCEPROP 1 LAST PATH I192
J 0
(-3277 3975);
DISPLAY 0.872340 (-3277 3975);
PAINT GREEN (-3277 3975);
DISPLAY INVISIBLE (-3277 3975);
FORCEADD TAP..1
(-3475 4025);
FORCEPROP 3 LASTPIN (-3525 4025) SIG_NAME M_D_CPU1_SA_DQS_DP<2>
J 0
(-3515 4035);
DISPLAY 0.659574 (-3515 4035);
PAINT MONO (-3515 4035);
DISPLAY INVISIBLE (-3515 4035);
FORCEPROP 1 LASTPIN (-3525 4025) BN 2
J 0
(-3537 4033);
DISPLAY 0.489362 (-3537 4033);
PAINT GREEN (-3537 4033);
FORCEPROP 2 LAST CDS_LIB mstr_standard
J 0
(-3475 4025);
DISPLAY 0.723404 (-3475 4025);
PAINT MONO (-3475 4025);
DISPLAY INVISIBLE (-3475 4025);
FORCEPROP 1 LAST BODY_TYPE PLUMBING
J 0
(-3475 4075);
DISPLAY 0.872340 (-3475 4075);
PAINT GREEN (-3475 4075);
DISPLAY INVISIBLE (-3475 4075);
FORCEPROP 1 LAST HDL_TAP TRUE
J 0
(-3150 3900);
DISPLAY 0.872340 (-3150 3900);
DISPLAY INVISIBLE (-3150 3900);
FORCEPROP 1 LAST PATH I193
J 0
(-3477 4025);
DISPLAY 0.872340 (-3477 4025);
PAINT GREEN (-3477 4025);
DISPLAY INVISIBLE (-3477 4025);
FORCEADD TAP..1
(-3475 4125);
FORCEPROP 3 LASTPIN (-3525 4125) SIG_NAME M_D_CPU1_SA_DQS_DP<3>
J 0
(-3515 4135);
DISPLAY 0.659574 (-3515 4135);
PAINT MONO (-3515 4135);
DISPLAY INVISIBLE (-3515 4135);
FORCEPROP 1 LASTPIN (-3525 4125) BN 3
J 0
(-3537 4133);
DISPLAY 0.489362 (-3537 4133);
PAINT GREEN (-3537 4133);
FORCEPROP 2 LAST CDS_LIB mstr_standard
J 0
(-3475 4125);
DISPLAY 0.723404 (-3475 4125);
PAINT MONO (-3475 4125);
DISPLAY INVISIBLE (-3475 4125);
FORCEPROP 1 LAST BODY_TYPE PLUMBING
J 0
(-3475 4175);
DISPLAY 0.872340 (-3475 4175);
PAINT GREEN (-3475 4175);
DISPLAY INVISIBLE (-3475 4175);
FORCEPROP 1 LAST HDL_TAP TRUE
J 0
(-3150 4000);
DISPLAY 0.872340 (-3150 4000);
DISPLAY INVISIBLE (-3150 4000);
FORCEPROP 1 LAST PATH I194
J 0
(-3477 4125);
DISPLAY 0.872340 (-3477 4125);
PAINT GREEN (-3477 4125);
DISPLAY INVISIBLE (-3477 4125);
FORCEADD OFFPAGE..2
(-2475 4775);
FORCEPROP 2 LAST $XR0 40 
J 0
(-2286 4775);
DISPLAY 0.638298 (-2286 4775);
PAINT MONO (-2286 4775);
FORCEPROP 2 LAST CDS_LIB mstr_standard
J 0
(-2475 4775);
DISPLAY 0.723404 (-2475 4775);
PAINT MONO (-2475 4775);
DISPLAY INVISIBLE (-2475 4775);
FORCEPROP 1 LAST OFFPAGE TRUE
J 0
(-2150 4650);
DISPLAY 0.723404 (-2150 4650);
PAINT GREEN (-2150 4650);
DISPLAY INVISIBLE (-2150 4650);
FORCEPROP 1 LAST COMMENT_BODY TRUE
J 0
(-2520 4680);
DISPLAY 0.872340 (-2520 4680);
PAINT GREEN (-2520 4680);
DISPLAY INVISIBLE (-2520 4680);
FORCEPROP 2 LAST PATH I196
J 0
(-2275 4825);
DISPLAY 0.680851 (-2275 4825);
DISPLAY INVISIBLE (-2275 4825);
FORCEADD OFFPAGE..2
(-2475 4725);
FORCEPROP 2 LAST $XR0 40 
J 0
(-2286 4725);
DISPLAY 0.638298 (-2286 4725);
PAINT MONO (-2286 4725);
FORCEPROP 2 LAST CDS_LIB mstr_standard
J 0
(-2475 4725);
DISPLAY 0.723404 (-2475 4725);
PAINT MONO (-2475 4725);
DISPLAY INVISIBLE (-2475 4725);
FORCEPROP 1 LAST OFFPAGE TRUE
J 0
(-2150 4600);
DISPLAY 0.723404 (-2150 4600);
PAINT GREEN (-2150 4600);
DISPLAY INVISIBLE (-2150 4600);
FORCEPROP 1 LAST COMMENT_BODY TRUE
J 0
(-2520 4630);
DISPLAY 0.872340 (-2520 4630);
PAINT GREEN (-2520 4630);
DISPLAY INVISIBLE (-2520 4630);
FORCEPROP 2 LAST PATH I197
J 0
(-2275 4775);
DISPLAY 0.680851 (-2275 4775);
DISPLAY INVISIBLE (-2275 4775);
FORCEADD TAP..1
(-3275 4675);
FORCEPROP 3 LASTPIN (-3325 4675) SIG_NAME M_D_CPU1_SA_DQS_DN<9>
J 0
(-3315 4685);
DISPLAY 0.659574 (-3315 4685);
PAINT MONO (-3315 4685);
DISPLAY INVISIBLE (-3315 4685);
FORCEPROP 1 LASTPIN (-3325 4675) BN 9
J 0
(-3337 4683);
DISPLAY 0.489362 (-3337 4683);
PAINT GREEN (-3337 4683);
FORCEPROP 2 LAST CDS_LIB mstr_standard
J 0
(-3275 4675);
DISPLAY 0.723404 (-3275 4675);
PAINT MONO (-3275 4675);
DISPLAY INVISIBLE (-3275 4675);
FORCEPROP 1 LAST BODY_TYPE PLUMBING
J 0
(-3275 4725);
DISPLAY 0.872340 (-3275 4725);
PAINT GREEN (-3275 4725);
DISPLAY INVISIBLE (-3275 4725);
FORCEPROP 1 LAST HDL_TAP TRUE
J 0
(-2950 4550);
DISPLAY 0.872340 (-2950 4550);
DISPLAY INVISIBLE (-2950 4550);
FORCEPROP 1 LAST PATH I198
J 0
(-3277 4675);
DISPLAY 0.872340 (-3277 4675);
PAINT GREEN (-3277 4675);
DISPLAY INVISIBLE (-3277 4675);
FORCEADD TAP..1
(-3275 4575);
FORCEPROP 3 LASTPIN (-3325 4575) SIG_NAME M_D_CPU1_SA_DQS_DN<8>
J 0
(-3315 4585);
DISPLAY 0.659574 (-3315 4585);
PAINT MONO (-3315 4585);
DISPLAY INVISIBLE (-3315 4585);
FORCEPROP 1 LASTPIN (-3325 4575) BN 8
J 0
(-3337 4583);
DISPLAY 0.489362 (-3337 4583);
PAINT GREEN (-3337 4583);
FORCEPROP 2 LAST CDS_LIB mstr_standard
J 0
(-3275 4575);
DISPLAY 0.723404 (-3275 4575);
PAINT MONO (-3275 4575);
DISPLAY INVISIBLE (-3275 4575);
FORCEPROP 1 LAST BODY_TYPE PLUMBING
J 0
(-3275 4625);
DISPLAY 0.872340 (-3275 4625);
PAINT GREEN (-3275 4625);
DISPLAY INVISIBLE (-3275 4625);
FORCEPROP 1 LAST HDL_TAP TRUE
J 0
(-2950 4450);
DISPLAY 0.872340 (-2950 4450);
DISPLAY INVISIBLE (-2950 4450);
FORCEPROP 1 LAST PATH I199
J 0
(-3277 4575);
DISPLAY 0.872340 (-3277 4575);
PAINT GREEN (-3277 4575);
DISPLAY INVISIBLE (-3277 4575);
FORCEADD OFFPAGE..5
(-8400 2175);
FORCEPROP 2 LAST $XR0 40 
J 0
(-8654 2175);
DISPLAY 0.638298 (-8654 2175);
PAINT MONO (-8654 2175);
FORCEPROP 2 LAST CDS_LIB mstr_standard
J 0
(-8400 2175);
DISPLAY 0.808511 (-8400 2175);
DISPLAY INVISIBLE (-8400 2175);
FORCEPROP 1 LAST OFFPAGE TRUE
J 0
(-8075 2050);
DISPLAY 0.872340 (-8075 2050);
PAINT GREEN (-8075 2050);
DISPLAY INVISIBLE (-8075 2050);
FORCEPROP 1 LAST COMMENT_BODY TRUE
J 0
(-8300 2100);
DISPLAY 0.872340 (-8300 2100);
PAINT GREEN (-8300 2100);
DISPLAY INVISIBLE (-8300 2100);
FORCEPROP 2 LAST PATH I2
J 0
(-8600 2225);
DISPLAY 1.021277 (-8600 2225);
DISPLAY INVISIBLE (-8600 2225);
FORCEADD TAP..1
R 2
(-7800 3825);
FORCEPROP 3 LASTPIN (-7750 3825) SIG_NAME M_D_CPU1_SA_CB<0>
J 0
(-7740 3835);
DISPLAY 0.659574 (-7740 3835);
PAINT MONO (-7740 3835);
DISPLAY INVISIBLE (-7740 3835);
FORCEPROP 1 LASTPIN (-7750 3825) BN 0
J 2
(-7738 3833);
DISPLAY 0.489362 (-7738 3833);
PAINT GREEN (-7738 3833);
FORCEPROP 2 LAST CDS_LIB mstr_standard
J 0
(-7800 3825);
DISPLAY 0.723404 (-7800 3825);
PAINT MONO (-7800 3825);
DISPLAY INVISIBLE (-7800 3825);
FORCEPROP 1 LAST BODY_TYPE PLUMBING
J 2
(-7800 3875);
DISPLAY 0.872340 (-7800 3875);
PAINT GREEN (-7800 3875);
DISPLAY INVISIBLE (-7800 3875);
FORCEPROP 1 LAST HDL_TAP TRUE
J 2
(-8125 3700);
DISPLAY 0.872340 (-8125 3700);
DISPLAY INVISIBLE (-8125 3700);
FORCEPROP 1 LAST PATH I20
J 2
(-7798 3825);
DISPLAY 0.872340 (-7798 3825);
PAINT GREEN (-7798 3825);
DISPLAY INVISIBLE (-7798 3825);
FORCEADD TAP..1
(-3275 4475);
FORCEPROP 3 LASTPIN (-3325 4475) SIG_NAME M_D_CPU1_SA_DQS_DN<7>
J 0
(-3315 4485);
DISPLAY 0.659574 (-3315 4485);
PAINT MONO (-3315 4485);
DISPLAY INVISIBLE (-3315 4485);
FORCEPROP 1 LASTPIN (-3325 4475) BN 7
J 0
(-3337 4483);
DISPLAY 0.489362 (-3337 4483);
PAINT GREEN (-3337 4483);
FORCEPROP 2 LAST CDS_LIB mstr_standard
J 0
(-3275 4475);
DISPLAY 0.723404 (-3275 4475);
PAINT MONO (-3275 4475);
DISPLAY INVISIBLE (-3275 4475);
FORCEPROP 1 LAST BODY_TYPE PLUMBING
J 0
(-3275 4525);
DISPLAY 0.872340 (-3275 4525);
PAINT GREEN (-3275 4525);
DISPLAY INVISIBLE (-3275 4525);
FORCEPROP 1 LAST HDL_TAP TRUE
J 0
(-2950 4350);
DISPLAY 0.872340 (-2950 4350);
DISPLAY INVISIBLE (-2950 4350);
FORCEPROP 1 LAST PATH I200
J 0
(-3277 4475);
DISPLAY 0.872340 (-3277 4475);
PAINT GREEN (-3277 4475);
DISPLAY INVISIBLE (-3277 4475);
FORCEADD TAP..1
(-3275 4375);
FORCEPROP 3 LASTPIN (-3325 4375) SIG_NAME M_D_CPU1_SA_DQS_DN<6>
J 0
(-3315 4385);
DISPLAY 0.659574 (-3315 4385);
PAINT MONO (-3315 4385);
DISPLAY INVISIBLE (-3315 4385);
FORCEPROP 1 LASTPIN (-3325 4375) BN 6
J 0
(-3337 4383);
DISPLAY 0.489362 (-3337 4383);
PAINT GREEN (-3337 4383);
FORCEPROP 2 LAST CDS_LIB mstr_standard
J 0
(-3275 4375);
DISPLAY 0.723404 (-3275 4375);
PAINT MONO (-3275 4375);
DISPLAY INVISIBLE (-3275 4375);
FORCEPROP 1 LAST BODY_TYPE PLUMBING
J 0
(-3275 4425);
DISPLAY 0.872340 (-3275 4425);
PAINT GREEN (-3275 4425);
DISPLAY INVISIBLE (-3275 4425);
FORCEPROP 1 LAST HDL_TAP TRUE
J 0
(-2950 4250);
DISPLAY 0.872340 (-2950 4250);
DISPLAY INVISIBLE (-2950 4250);
FORCEPROP 1 LAST PATH I201
J 0
(-3277 4375);
DISPLAY 0.872340 (-3277 4375);
PAINT GREEN (-3277 4375);
DISPLAY INVISIBLE (-3277 4375);
FORCEADD TAP..1
(-3475 4625);
FORCEPROP 3 LASTPIN (-3525 4625) SIG_NAME M_D_CPU1_SA_DQS_DP<8>
J 0
(-3515 4635);
DISPLAY 0.659574 (-3515 4635);
PAINT MONO (-3515 4635);
DISPLAY INVISIBLE (-3515 4635);
FORCEPROP 1 LASTPIN (-3525 4625) BN 8
J 0
(-3537 4633);
DISPLAY 0.489362 (-3537 4633);
PAINT GREEN (-3537 4633);
FORCEPROP 2 LAST CDS_LIB mstr_standard
J 0
(-3475 4625);
DISPLAY 0.723404 (-3475 4625);
PAINT MONO (-3475 4625);
DISPLAY INVISIBLE (-3475 4625);
FORCEPROP 1 LAST BODY_TYPE PLUMBING
J 0
(-3475 4675);
DISPLAY 0.872340 (-3475 4675);
PAINT GREEN (-3475 4675);
DISPLAY INVISIBLE (-3475 4675);
FORCEPROP 1 LAST HDL_TAP TRUE
J 0
(-3150 4500);
DISPLAY 0.872340 (-3150 4500);
DISPLAY INVISIBLE (-3150 4500);
FORCEPROP 1 LAST PATH I202
J 0
(-3477 4625);
DISPLAY 0.872340 (-3477 4625);
PAINT GREEN (-3477 4625);
DISPLAY INVISIBLE (-3477 4625);
FORCEADD TAP..1
(-3475 4725);
FORCEPROP 3 LASTPIN (-3525 4725) SIG_NAME M_D_CPU1_SA_DQS_DP<9>
J 0
(-3515 4735);
DISPLAY 0.659574 (-3515 4735);
PAINT MONO (-3515 4735);
DISPLAY INVISIBLE (-3515 4735);
FORCEPROP 1 LASTPIN (-3525 4725) BN 9
J 0
(-3537 4733);
DISPLAY 0.489362 (-3537 4733);
PAINT GREEN (-3537 4733);
FORCEPROP 2 LAST CDS_LIB mstr_standard
J 0
(-3475 4725);
DISPLAY 0.723404 (-3475 4725);
PAINT MONO (-3475 4725);
DISPLAY INVISIBLE (-3475 4725);
FORCEPROP 1 LAST BODY_TYPE PLUMBING
J 0
(-3475 4775);
DISPLAY 0.872340 (-3475 4775);
PAINT GREEN (-3475 4775);
DISPLAY INVISIBLE (-3475 4775);
FORCEPROP 1 LAST HDL_TAP TRUE
J 0
(-3150 4600);
DISPLAY 0.872340 (-3150 4600);
DISPLAY INVISIBLE (-3150 4600);
FORCEPROP 1 LAST PATH I203
J 0
(-3477 4725);
DISPLAY 0.872340 (-3477 4725);
PAINT GREEN (-3477 4725);
DISPLAY INVISIBLE (-3477 4725);
FORCEADD TAP..1
(-3475 4425);
FORCEPROP 3 LASTPIN (-3525 4425) SIG_NAME M_D_CPU1_SA_DQS_DP<6>
J 0
(-3515 4435);
DISPLAY 0.659574 (-3515 4435);
PAINT MONO (-3515 4435);
DISPLAY INVISIBLE (-3515 4435);
FORCEPROP 1 LASTPIN (-3525 4425) BN 6
J 0
(-3537 4433);
DISPLAY 0.489362 (-3537 4433);
PAINT GREEN (-3537 4433);
FORCEPROP 2 LAST CDS_LIB mstr_standard
J 0
(-3475 4425);
DISPLAY 0.723404 (-3475 4425);
PAINT MONO (-3475 4425);
DISPLAY INVISIBLE (-3475 4425);
FORCEPROP 1 LAST BODY_TYPE PLUMBING
J 0
(-3475 4475);
DISPLAY 0.872340 (-3475 4475);
PAINT GREEN (-3475 4475);
DISPLAY INVISIBLE (-3475 4475);
FORCEPROP 1 LAST HDL_TAP TRUE
J 0
(-3150 4300);
DISPLAY 0.872340 (-3150 4300);
DISPLAY INVISIBLE (-3150 4300);
FORCEPROP 1 LAST PATH I204
J 0
(-3477 4425);
DISPLAY 0.872340 (-3477 4425);
PAINT GREEN (-3477 4425);
DISPLAY INVISIBLE (-3477 4425);
FORCEADD TAP..1
(-3475 4525);
FORCEPROP 3 LASTPIN (-3525 4525) SIG_NAME M_D_CPU1_SA_DQS_DP<7>
J 0
(-3515 4535);
DISPLAY 0.659574 (-3515 4535);
PAINT MONO (-3515 4535);
DISPLAY INVISIBLE (-3515 4535);
FORCEPROP 1 LASTPIN (-3525 4525) BN 7
J 0
(-3537 4533);
DISPLAY 0.489362 (-3537 4533);
PAINT GREEN (-3537 4533);
FORCEPROP 2 LAST CDS_LIB mstr_standard
J 0
(-3475 4525);
DISPLAY 0.723404 (-3475 4525);
PAINT MONO (-3475 4525);
DISPLAY INVISIBLE (-3475 4525);
FORCEPROP 1 LAST BODY_TYPE PLUMBING
J 0
(-3475 4575);
DISPLAY 0.872340 (-3475 4575);
PAINT GREEN (-3475 4575);
DISPLAY INVISIBLE (-3475 4575);
FORCEPROP 1 LAST HDL_TAP TRUE
J 0
(-3150 4400);
DISPLAY 0.872340 (-3150 4400);
DISPLAY INVISIBLE (-3150 4400);
FORCEPROP 1 LAST PATH I205
J 0
(-3477 4525);
DISPLAY 0.872340 (-3477 4525);
PAINT GREEN (-3477 4525);
DISPLAY INVISIBLE (-3477 4525);
FORCEADD TAP..1
(-3475 4325);
FORCEPROP 3 LASTPIN (-3525 4325) SIG_NAME M_D_CPU1_SA_DQS_DP<5>
J 0
(-3515 4335);
DISPLAY 0.659574 (-3515 4335);
PAINT MONO (-3515 4335);
DISPLAY INVISIBLE (-3515 4335);
FORCEPROP 1 LASTPIN (-3525 4325) BN 5
J 0
(-3537 4333);
DISPLAY 0.489362 (-3537 4333);
PAINT GREEN (-3537 4333);
FORCEPROP 2 LAST CDS_LIB mstr_standard
J 0
(-3475 4325);
DISPLAY 0.723404 (-3475 4325);
PAINT MONO (-3475 4325);
DISPLAY INVISIBLE (-3475 4325);
FORCEPROP 1 LAST BODY_TYPE PLUMBING
J 0
(-3475 4375);
DISPLAY 0.872340 (-3475 4375);
PAINT GREEN (-3475 4375);
DISPLAY INVISIBLE (-3475 4375);
FORCEPROP 1 LAST HDL_TAP TRUE
J 0
(-3150 4200);
DISPLAY 0.872340 (-3150 4200);
DISPLAY INVISIBLE (-3150 4200);
FORCEPROP 1 LAST PATH I206
J 0
(-3477 4325);
DISPLAY 0.872340 (-3477 4325);
PAINT GREEN (-3477 4325);
DISPLAY INVISIBLE (-3477 4325);
FORCEADD TAP..1
(-3275 4275);
FORCEPROP 3 LASTPIN (-3325 4275) SIG_NAME M_D_CPU1_SA_DQS_DN<5>
J 0
(-3315 4285);
DISPLAY 0.659574 (-3315 4285);
PAINT MONO (-3315 4285);
DISPLAY INVISIBLE (-3315 4285);
FORCEPROP 1 LASTPIN (-3325 4275) BN 5
J 0
(-3337 4283);
DISPLAY 0.489362 (-3337 4283);
PAINT GREEN (-3337 4283);
FORCEPROP 2 LAST CDS_LIB mstr_standard
J 0
(-3275 4275);
DISPLAY 0.723404 (-3275 4275);
PAINT MONO (-3275 4275);
DISPLAY INVISIBLE (-3275 4275);
FORCEPROP 1 LAST BODY_TYPE PLUMBING
J 0
(-3275 4325);
DISPLAY 0.872340 (-3275 4325);
PAINT GREEN (-3275 4325);
DISPLAY INVISIBLE (-3275 4325);
FORCEPROP 1 LAST HDL_TAP TRUE
J 0
(-2950 4150);
DISPLAY 0.872340 (-2950 4150);
DISPLAY INVISIBLE (-2950 4150);
FORCEPROP 1 LAST PATH I207
J 0
(-3277 4275);
DISPLAY 0.872340 (-3277 4275);
PAINT GREEN (-3277 4275);
DISPLAY INVISIBLE (-3277 4275);
FORCEADD TAP..1
(-3275 4175);
FORCEPROP 3 LASTPIN (-3325 4175) SIG_NAME M_D_CPU1_SA_DQS_DN<4>
J 0
(-3315 4185);
DISPLAY 0.659574 (-3315 4185);
PAINT MONO (-3315 4185);
DISPLAY INVISIBLE (-3315 4185);
FORCEPROP 1 LASTPIN (-3325 4175) BN 4
J 0
(-3337 4183);
DISPLAY 0.489362 (-3337 4183);
PAINT GREEN (-3337 4183);
FORCEPROP 2 LAST CDS_LIB mstr_standard
J 0
(-3275 4175);
DISPLAY 0.723404 (-3275 4175);
PAINT MONO (-3275 4175);
DISPLAY INVISIBLE (-3275 4175);
FORCEPROP 1 LAST BODY_TYPE PLUMBING
J 0
(-3275 4225);
DISPLAY 0.872340 (-3275 4225);
PAINT GREEN (-3275 4225);
DISPLAY INVISIBLE (-3275 4225);
FORCEPROP 1 LAST HDL_TAP TRUE
J 0
(-2950 4050);
DISPLAY 0.872340 (-2950 4050);
DISPLAY INVISIBLE (-2950 4050);
FORCEPROP 1 LAST PATH I208
J 0
(-3277 4175);
DISPLAY 0.872340 (-3277 4175);
PAINT GREEN (-3277 4175);
DISPLAY INVISIBLE (-3277 4175);
FORCEADD TAP..1
(-3275 4075);
FORCEPROP 3 LASTPIN (-3325 4075) SIG_NAME M_D_CPU1_SA_DQS_DN<3>
J 0
(-3315 4085);
DISPLAY 0.659574 (-3315 4085);
PAINT MONO (-3315 4085);
DISPLAY INVISIBLE (-3315 4085);
FORCEPROP 1 LASTPIN (-3325 4075) BN 3
J 0
(-3337 4083);
DISPLAY 0.489362 (-3337 4083);
PAINT GREEN (-3337 4083);
FORCEPROP 2 LAST CDS_LIB mstr_standard
J 0
(-3275 4075);
DISPLAY 0.723404 (-3275 4075);
PAINT MONO (-3275 4075);
DISPLAY INVISIBLE (-3275 4075);
FORCEPROP 1 LAST BODY_TYPE PLUMBING
J 0
(-3275 4125);
DISPLAY 0.872340 (-3275 4125);
PAINT GREEN (-3275 4125);
DISPLAY INVISIBLE (-3275 4125);
FORCEPROP 1 LAST HDL_TAP TRUE
J 0
(-2950 3950);
DISPLAY 0.872340 (-2950 3950);
DISPLAY INVISIBLE (-2950 3950);
FORCEPROP 1 LAST PATH I209
J 0
(-3277 4075);
DISPLAY 0.872340 (-3277 4075);
PAINT GREEN (-3277 4075);
DISPLAY INVISIBLE (-3277 4075);
FORCEADD TAP..1
R 2
(-7800 3725);
FORCEPROP 3 LASTPIN (-7750 3725) SIG_NAME M_D_CPU1_SB_CB<7>
J 0
(-7740 3735);
DISPLAY 0.659574 (-7740 3735);
PAINT MONO (-7740 3735);
DISPLAY INVISIBLE (-7740 3735);
FORCEPROP 1 LASTPIN (-7750 3725) BN 7
J 2
(-7738 3733);
DISPLAY 0.489362 (-7738 3733);
PAINT GREEN (-7738 3733);
FORCEPROP 2 LAST CDS_LIB mstr_standard
J 0
(-7800 3725);
DISPLAY 0.723404 (-7800 3725);
PAINT MONO (-7800 3725);
DISPLAY INVISIBLE (-7800 3725);
FORCEPROP 1 LAST BODY_TYPE PLUMBING
J 2
(-7800 3775);
DISPLAY 0.872340 (-7800 3775);
PAINT GREEN (-7800 3775);
DISPLAY INVISIBLE (-7800 3775);
FORCEPROP 1 LAST HDL_TAP TRUE
J 2
(-8125 3600);
DISPLAY 0.872340 (-8125 3600);
DISPLAY INVISIBLE (-8125 3600);
FORCEPROP 1 LAST PATH I21
J 2
(-7798 3725);
DISPLAY 0.872340 (-7798 3725);
PAINT GREEN (-7798 3725);
DISPLAY INVISIBLE (-7798 3725);
FORCEADD TAP..1
(-3475 4225);
FORCEPROP 3 LASTPIN (-3525 4225) SIG_NAME M_D_CPU1_SA_DQS_DP<4>
J 0
(-3515 4235);
DISPLAY 0.659574 (-3515 4235);
PAINT MONO (-3515 4235);
DISPLAY INVISIBLE (-3515 4235);
FORCEPROP 1 LASTPIN (-3525 4225) BN 4
J 0
(-3537 4233);
DISPLAY 0.489362 (-3537 4233);
PAINT GREEN (-3537 4233);
FORCEPROP 2 LAST CDS_LIB mstr_standard
J 0
(-3475 4225);
DISPLAY 0.723404 (-3475 4225);
PAINT MONO (-3475 4225);
DISPLAY INVISIBLE (-3475 4225);
FORCEPROP 1 LAST BODY_TYPE PLUMBING
J 0
(-3475 4275);
DISPLAY 0.872340 (-3475 4275);
PAINT GREEN (-3475 4275);
DISPLAY INVISIBLE (-3475 4275);
FORCEPROP 1 LAST HDL_TAP TRUE
J 0
(-3150 4100);
DISPLAY 0.872340 (-3150 4100);
DISPLAY INVISIBLE (-3150 4100);
FORCEPROP 1 LAST PATH I210
J 0
(-3477 4225);
DISPLAY 0.872340 (-3477 4225);
PAINT GREEN (-3477 4225);
DISPLAY INVISIBLE (-3477 4225);
FORCEADD TAP..1
(-3475 3925);
FORCEPROP 3 LASTPIN (-3525 3925) SIG_NAME M_D_CPU1_SA_DQS_DP<1>
J 0
(-3515 3935);
DISPLAY 0.659574 (-3515 3935);
PAINT MONO (-3515 3935);
DISPLAY INVISIBLE (-3515 3935);
FORCEPROP 1 LASTPIN (-3525 3925) BN 1
J 0
(-3537 3933);
DISPLAY 0.489362 (-3537 3933);
PAINT GREEN (-3537 3933);
FORCEPROP 2 LAST CDS_LIB mstr_standard
J 0
(-3475 3925);
DISPLAY 0.723404 (-3475 3925);
PAINT MONO (-3475 3925);
DISPLAY INVISIBLE (-3475 3925);
FORCEPROP 1 LAST BODY_TYPE PLUMBING
J 0
(-3475 3975);
DISPLAY 0.872340 (-3475 3975);
PAINT GREEN (-3475 3975);
DISPLAY INVISIBLE (-3475 3975);
FORCEPROP 1 LAST HDL_TAP TRUE
J 0
(-3150 3800);
DISPLAY 0.872340 (-3150 3800);
DISPLAY INVISIBLE (-3150 3800);
FORCEPROP 1 LAST PATH I211
J 0
(-3477 3925);
DISPLAY 0.872340 (-3477 3925);
PAINT GREEN (-3477 3925);
DISPLAY INVISIBLE (-3477 3925);
FORCEADD TAP..1
(-3475 3825);
FORCEPROP 3 LASTPIN (-3525 3825) SIG_NAME M_D_CPU1_SA_DQS_DP<0>
J 0
(-3515 3835);
DISPLAY 0.659574 (-3515 3835);
PAINT MONO (-3515 3835);
DISPLAY INVISIBLE (-3515 3835);
FORCEPROP 1 LASTPIN (-3525 3825) BN 0
J 0
(-3537 3833);
DISPLAY 0.489362 (-3537 3833);
PAINT GREEN (-3537 3833);
FORCEPROP 2 LAST CDS_LIB mstr_standard
J 0
(-3475 3825);
DISPLAY 0.723404 (-3475 3825);
PAINT MONO (-3475 3825);
DISPLAY INVISIBLE (-3475 3825);
FORCEPROP 1 LAST BODY_TYPE PLUMBING
J 0
(-3475 3875);
DISPLAY 0.872340 (-3475 3875);
PAINT GREEN (-3475 3875);
DISPLAY INVISIBLE (-3475 3875);
FORCEPROP 1 LAST HDL_TAP TRUE
J 0
(-3150 3700);
DISPLAY 0.872340 (-3150 3700);
DISPLAY INVISIBLE (-3150 3700);
FORCEPROP 1 LAST PATH I212
J 0
(-3477 3825);
DISPLAY 0.872340 (-3477 3825);
PAINT GREEN (-3477 3825);
DISPLAY INVISIBLE (-3477 3825);
FORCEADD OFFPAGE..2
(-2475 3725);
FORCEPROP 2 LAST $XR0 40 
J 0
(-2286 3725);
DISPLAY 0.638298 (-2286 3725);
PAINT MONO (-2286 3725);
FORCEPROP 2 LAST CDS_LIB mstr_standard
J 0
(-2475 3725);
DISPLAY 0.723404 (-2475 3725);
PAINT MONO (-2475 3725);
DISPLAY INVISIBLE (-2475 3725);
FORCEPROP 1 LAST OFFPAGE TRUE
J 0
(-2150 3600);
DISPLAY 0.723404 (-2150 3600);
PAINT GREEN (-2150 3600);
DISPLAY INVISIBLE (-2150 3600);
FORCEPROP 1 LAST COMMENT_BODY TRUE
J 0
(-2520 3630);
DISPLAY 0.872340 (-2520 3630);
PAINT GREEN (-2520 3630);
DISPLAY INVISIBLE (-2520 3630);
FORCEPROP 2 LAST PATH I213
J 0
(-2275 3775);
DISPLAY 0.680851 (-2275 3775);
DISPLAY INVISIBLE (-2275 3775);
FORCEADD OFFPAGE..2
(-2475 3675);
FORCEPROP 2 LAST $XR0 40 
J 0
(-2286 3675);
DISPLAY 0.638298 (-2286 3675);
PAINT MONO (-2286 3675);
FORCEPROP 2 LAST CDS_LIB mstr_standard
J 0
(-2475 3675);
DISPLAY 0.723404 (-2475 3675);
PAINT MONO (-2475 3675);
DISPLAY INVISIBLE (-2475 3675);
FORCEPROP 1 LAST OFFPAGE TRUE
J 0
(-2150 3550);
DISPLAY 0.723404 (-2150 3550);
PAINT GREEN (-2150 3550);
DISPLAY INVISIBLE (-2150 3550);
FORCEPROP 1 LAST COMMENT_BODY TRUE
J 0
(-2520 3580);
DISPLAY 0.872340 (-2520 3580);
PAINT GREEN (-2520 3580);
DISPLAY INVISIBLE (-2520 3580);
FORCEPROP 2 LAST PATH I214
J 0
(-2275 3725);
DISPLAY 0.680851 (-2275 3725);
DISPLAY INVISIBLE (-2275 3725);
FORCEADD TAP..1
(-3275 3625);
FORCEPROP 3 LASTPIN (-3325 3625) SIG_NAME M_D_CPU1_SB_DQS_DN<9>
J 0
(-3315 3635);
DISPLAY 0.659574 (-3315 3635);
PAINT MONO (-3315 3635);
DISPLAY INVISIBLE (-3315 3635);
FORCEPROP 1 LASTPIN (-3325 3625) BN 9
J 0
(-3337 3633);
DISPLAY 0.489362 (-3337 3633);
PAINT GREEN (-3337 3633);
FORCEPROP 2 LAST CDS_LIB mstr_standard
J 0
(-3275 3625);
DISPLAY 0.723404 (-3275 3625);
PAINT MONO (-3275 3625);
DISPLAY INVISIBLE (-3275 3625);
FORCEPROP 1 LAST BODY_TYPE PLUMBING
J 0
(-3275 3675);
DISPLAY 0.872340 (-3275 3675);
PAINT GREEN (-3275 3675);
DISPLAY INVISIBLE (-3275 3675);
FORCEPROP 1 LAST HDL_TAP TRUE
J 0
(-2950 3500);
DISPLAY 0.872340 (-2950 3500);
DISPLAY INVISIBLE (-2950 3500);
FORCEPROP 1 LAST PATH I215
J 0
(-3277 3625);
DISPLAY 0.872340 (-3277 3625);
PAINT GREEN (-3277 3625);
DISPLAY INVISIBLE (-3277 3625);
FORCEADD TAP..1
(-3275 3775);
FORCEPROP 3 LASTPIN (-3325 3775) SIG_NAME M_D_CPU1_SA_DQS_DN<0>
J 0
(-3315 3785);
DISPLAY 0.659574 (-3315 3785);
PAINT MONO (-3315 3785);
DISPLAY INVISIBLE (-3315 3785);
FORCEPROP 1 LASTPIN (-3325 3775) BN 0
J 0
(-3337 3783);
DISPLAY 0.489362 (-3337 3783);
PAINT GREEN (-3337 3783);
FORCEPROP 2 LAST CDS_LIB mstr_standard
J 0
(-3275 3775);
DISPLAY 0.723404 (-3275 3775);
PAINT MONO (-3275 3775);
DISPLAY INVISIBLE (-3275 3775);
FORCEPROP 1 LAST BODY_TYPE PLUMBING
J 0
(-3275 3825);
DISPLAY 0.872340 (-3275 3825);
PAINT GREEN (-3275 3825);
DISPLAY INVISIBLE (-3275 3825);
FORCEPROP 1 LAST HDL_TAP TRUE
J 0
(-2950 3650);
DISPLAY 0.872340 (-2950 3650);
DISPLAY INVISIBLE (-2950 3650);
FORCEPROP 1 LAST PATH I216
J 0
(-3277 3775);
DISPLAY 0.872340 (-3277 3775);
PAINT GREEN (-3277 3775);
DISPLAY INVISIBLE (-3277 3775);
FORCEADD TAP..1
(-3275 3525);
FORCEPROP 3 LASTPIN (-3325 3525) SIG_NAME M_D_CPU1_SB_DQS_DN<8>
J 0
(-3315 3535);
DISPLAY 0.659574 (-3315 3535);
PAINT MONO (-3315 3535);
DISPLAY INVISIBLE (-3315 3535);
FORCEPROP 1 LASTPIN (-3325 3525) BN 8
J 0
(-3337 3533);
DISPLAY 0.489362 (-3337 3533);
PAINT GREEN (-3337 3533);
FORCEPROP 2 LAST CDS_LIB mstr_standard
J 0
(-3275 3525);
DISPLAY 0.723404 (-3275 3525);
PAINT MONO (-3275 3525);
DISPLAY INVISIBLE (-3275 3525);
FORCEPROP 1 LAST BODY_TYPE PLUMBING
J 0
(-3275 3575);
DISPLAY 0.872340 (-3275 3575);
PAINT GREEN (-3275 3575);
DISPLAY INVISIBLE (-3275 3575);
FORCEPROP 1 LAST HDL_TAP TRUE
J 0
(-2950 3400);
DISPLAY 0.872340 (-2950 3400);
DISPLAY INVISIBLE (-2950 3400);
FORCEPROP 1 LAST PATH I217
J 0
(-3277 3525);
DISPLAY 0.872340 (-3277 3525);
PAINT GREEN (-3277 3525);
DISPLAY INVISIBLE (-3277 3525);
FORCEADD TAP..1
(-3275 3425);
FORCEPROP 3 LASTPIN (-3325 3425) SIG_NAME M_D_CPU1_SB_DQS_DN<7>
J 0
(-3315 3435);
DISPLAY 0.659574 (-3315 3435);
PAINT MONO (-3315 3435);
DISPLAY INVISIBLE (-3315 3435);
FORCEPROP 1 LASTPIN (-3325 3425) BN 7
J 0
(-3337 3433);
DISPLAY 0.489362 (-3337 3433);
PAINT GREEN (-3337 3433);
FORCEPROP 2 LAST CDS_LIB mstr_standard
J 0
(-3275 3425);
DISPLAY 0.723404 (-3275 3425);
PAINT MONO (-3275 3425);
DISPLAY INVISIBLE (-3275 3425);
FORCEPROP 1 LAST BODY_TYPE PLUMBING
J 0
(-3275 3475);
DISPLAY 0.872340 (-3275 3475);
PAINT GREEN (-3275 3475);
DISPLAY INVISIBLE (-3275 3475);
FORCEPROP 1 LAST HDL_TAP TRUE
J 0
(-2950 3300);
DISPLAY 0.872340 (-2950 3300);
DISPLAY INVISIBLE (-2950 3300);
FORCEPROP 1 LAST PATH I218
J 0
(-3277 3425);
DISPLAY 0.872340 (-3277 3425);
PAINT GREEN (-3277 3425);
DISPLAY INVISIBLE (-3277 3425);
FORCEADD TAP..1
(-3275 3325);
FORCEPROP 3 LASTPIN (-3325 3325) SIG_NAME M_D_CPU1_SB_DQS_DN<6>
J 0
(-3315 3335);
DISPLAY 0.659574 (-3315 3335);
PAINT MONO (-3315 3335);
DISPLAY INVISIBLE (-3315 3335);
FORCEPROP 1 LASTPIN (-3325 3325) BN 6
J 0
(-3337 3333);
DISPLAY 0.489362 (-3337 3333);
PAINT GREEN (-3337 3333);
FORCEPROP 2 LAST CDS_LIB mstr_standard
J 0
(-3275 3325);
DISPLAY 0.723404 (-3275 3325);
PAINT MONO (-3275 3325);
DISPLAY INVISIBLE (-3275 3325);
FORCEPROP 1 LAST BODY_TYPE PLUMBING
J 0
(-3275 3375);
DISPLAY 0.872340 (-3275 3375);
PAINT GREEN (-3275 3375);
DISPLAY INVISIBLE (-3275 3375);
FORCEPROP 1 LAST HDL_TAP TRUE
J 0
(-2950 3200);
DISPLAY 0.872340 (-2950 3200);
DISPLAY INVISIBLE (-2950 3200);
FORCEPROP 1 LAST PATH I219
J 0
(-3277 3325);
DISPLAY 0.872340 (-3277 3325);
PAINT GREEN (-3277 3325);
DISPLAY INVISIBLE (-3277 3325);
FORCEADD TAP..1
R 2
(-7800 3925);
FORCEPROP 3 LASTPIN (-7750 3925) SIG_NAME M_D_CPU1_SA_CB<2>
J 0
(-7740 3935);
DISPLAY 0.659574 (-7740 3935);
PAINT MONO (-7740 3935);
DISPLAY INVISIBLE (-7740 3935);
FORCEPROP 1 LASTPIN (-7750 3925) BN 2
J 2
(-7738 3933);
DISPLAY 0.489362 (-7738 3933);
PAINT GREEN (-7738 3933);
FORCEPROP 2 LAST CDS_LIB mstr_standard
J 0
(-7800 3925);
DISPLAY 0.723404 (-7800 3925);
PAINT MONO (-7800 3925);
DISPLAY INVISIBLE (-7800 3925);
FORCEPROP 1 LAST BODY_TYPE PLUMBING
J 2
(-7800 3975);
DISPLAY 0.872340 (-7800 3975);
PAINT GREEN (-7800 3975);
DISPLAY INVISIBLE (-7800 3975);
FORCEPROP 1 LAST HDL_TAP TRUE
J 2
(-8125 3800);
DISPLAY 0.872340 (-8125 3800);
DISPLAY INVISIBLE (-8125 3800);
FORCEPROP 1 LAST PATH I22
J 2
(-7798 3925);
DISPLAY 0.872340 (-7798 3925);
PAINT GREEN (-7798 3925);
DISPLAY INVISIBLE (-7798 3925);
FORCEADD TAP..1
(-3475 3575);
FORCEPROP 3 LASTPIN (-3525 3575) SIG_NAME M_D_CPU1_SB_DQS_DP<8>
J 0
(-3515 3585);
DISPLAY 0.659574 (-3515 3585);
PAINT MONO (-3515 3585);
DISPLAY INVISIBLE (-3515 3585);
FORCEPROP 1 LASTPIN (-3525 3575) BN 8
J 0
(-3537 3583);
DISPLAY 0.489362 (-3537 3583);
PAINT GREEN (-3537 3583);
FORCEPROP 2 LAST CDS_LIB mstr_standard
J 0
(-3475 3575);
DISPLAY 0.723404 (-3475 3575);
PAINT MONO (-3475 3575);
DISPLAY INVISIBLE (-3475 3575);
FORCEPROP 1 LAST BODY_TYPE PLUMBING
J 0
(-3475 3625);
DISPLAY 0.872340 (-3475 3625);
PAINT GREEN (-3475 3625);
DISPLAY INVISIBLE (-3475 3625);
FORCEPROP 1 LAST HDL_TAP TRUE
J 0
(-3150 3450);
DISPLAY 0.872340 (-3150 3450);
DISPLAY INVISIBLE (-3150 3450);
FORCEPROP 1 LAST PATH I220
J 0
(-3477 3575);
DISPLAY 0.872340 (-3477 3575);
PAINT GREEN (-3477 3575);
DISPLAY INVISIBLE (-3477 3575);
FORCEADD TAP..1
(-3475 3675);
FORCEPROP 3 LASTPIN (-3525 3675) SIG_NAME M_D_CPU1_SB_DQS_DP<9>
J 0
(-3515 3685);
DISPLAY 0.659574 (-3515 3685);
PAINT MONO (-3515 3685);
DISPLAY INVISIBLE (-3515 3685);
FORCEPROP 1 LASTPIN (-3525 3675) BN 9
J 0
(-3537 3683);
DISPLAY 0.489362 (-3537 3683);
PAINT GREEN (-3537 3683);
FORCEPROP 2 LAST CDS_LIB mstr_standard
J 0
(-3475 3675);
DISPLAY 0.723404 (-3475 3675);
PAINT MONO (-3475 3675);
DISPLAY INVISIBLE (-3475 3675);
FORCEPROP 1 LAST BODY_TYPE PLUMBING
J 0
(-3475 3725);
DISPLAY 0.872340 (-3475 3725);
PAINT GREEN (-3475 3725);
DISPLAY INVISIBLE (-3475 3725);
FORCEPROP 1 LAST HDL_TAP TRUE
J 0
(-3150 3550);
DISPLAY 0.872340 (-3150 3550);
DISPLAY INVISIBLE (-3150 3550);
FORCEPROP 1 LAST PATH I221
J 0
(-3477 3675);
DISPLAY 0.872340 (-3477 3675);
PAINT GREEN (-3477 3675);
DISPLAY INVISIBLE (-3477 3675);
FORCEADD TAP..1
(-3475 3375);
FORCEPROP 3 LASTPIN (-3525 3375) SIG_NAME M_D_CPU1_SB_DQS_DP<6>
J 0
(-3515 3385);
DISPLAY 0.659574 (-3515 3385);
PAINT MONO (-3515 3385);
DISPLAY INVISIBLE (-3515 3385);
FORCEPROP 1 LASTPIN (-3525 3375) BN 6
J 0
(-3537 3383);
DISPLAY 0.489362 (-3537 3383);
PAINT GREEN (-3537 3383);
FORCEPROP 2 LAST CDS_LIB mstr_standard
J 0
(-3475 3375);
DISPLAY 0.723404 (-3475 3375);
PAINT MONO (-3475 3375);
DISPLAY INVISIBLE (-3475 3375);
FORCEPROP 1 LAST BODY_TYPE PLUMBING
J 0
(-3475 3425);
DISPLAY 0.872340 (-3475 3425);
PAINT GREEN (-3475 3425);
DISPLAY INVISIBLE (-3475 3425);
FORCEPROP 1 LAST HDL_TAP TRUE
J 0
(-3150 3250);
DISPLAY 0.872340 (-3150 3250);
DISPLAY INVISIBLE (-3150 3250);
FORCEPROP 1 LAST PATH I222
J 0
(-3477 3375);
DISPLAY 0.872340 (-3477 3375);
PAINT GREEN (-3477 3375);
DISPLAY INVISIBLE (-3477 3375);
FORCEADD TAP..1
(-3475 3475);
FORCEPROP 3 LASTPIN (-3525 3475) SIG_NAME M_D_CPU1_SB_DQS_DP<7>
J 0
(-3515 3485);
DISPLAY 0.659574 (-3515 3485);
PAINT MONO (-3515 3485);
DISPLAY INVISIBLE (-3515 3485);
FORCEPROP 1 LASTPIN (-3525 3475) BN 7
J 0
(-3537 3483);
DISPLAY 0.489362 (-3537 3483);
PAINT GREEN (-3537 3483);
FORCEPROP 2 LAST CDS_LIB mstr_standard
J 0
(-3475 3475);
DISPLAY 0.723404 (-3475 3475);
PAINT MONO (-3475 3475);
DISPLAY INVISIBLE (-3475 3475);
FORCEPROP 1 LAST BODY_TYPE PLUMBING
J 0
(-3475 3525);
DISPLAY 0.872340 (-3475 3525);
PAINT GREEN (-3475 3525);
DISPLAY INVISIBLE (-3475 3525);
FORCEPROP 1 LAST HDL_TAP TRUE
J 0
(-3150 3350);
DISPLAY 0.872340 (-3150 3350);
DISPLAY INVISIBLE (-3150 3350);
FORCEPROP 1 LAST PATH I223
J 0
(-3477 3475);
DISPLAY 0.872340 (-3477 3475);
PAINT GREEN (-3477 3475);
DISPLAY INVISIBLE (-3477 3475);
FORCEADD TAP..1
(-3275 3225);
FORCEPROP 3 LASTPIN (-3325 3225) SIG_NAME M_D_CPU1_SB_DQS_DN<5>
J 0
(-3315 3235);
DISPLAY 0.659574 (-3315 3235);
PAINT MONO (-3315 3235);
DISPLAY INVISIBLE (-3315 3235);
FORCEPROP 1 LASTPIN (-3325 3225) BN 5
J 0
(-3337 3233);
DISPLAY 0.489362 (-3337 3233);
PAINT GREEN (-3337 3233);
FORCEPROP 2 LAST CDS_LIB mstr_standard
J 0
(-3275 3225);
DISPLAY 0.723404 (-3275 3225);
PAINT MONO (-3275 3225);
DISPLAY INVISIBLE (-3275 3225);
FORCEPROP 1 LAST BODY_TYPE PLUMBING
J 0
(-3275 3275);
DISPLAY 0.872340 (-3275 3275);
PAINT GREEN (-3275 3275);
DISPLAY INVISIBLE (-3275 3275);
FORCEPROP 1 LAST HDL_TAP TRUE
J 0
(-2950 3100);
DISPLAY 0.872340 (-2950 3100);
DISPLAY INVISIBLE (-2950 3100);
FORCEPROP 1 LAST PATH I224
J 0
(-3277 3225);
DISPLAY 0.872340 (-3277 3225);
PAINT GREEN (-3277 3225);
DISPLAY INVISIBLE (-3277 3225);
FORCEADD TAP..1
(-3275 3125);
FORCEPROP 3 LASTPIN (-3325 3125) SIG_NAME M_D_CPU1_SB_DQS_DN<4>
J 0
(-3315 3135);
DISPLAY 0.659574 (-3315 3135);
PAINT MONO (-3315 3135);
DISPLAY INVISIBLE (-3315 3135);
FORCEPROP 1 LASTPIN (-3325 3125) BN 4
J 0
(-3337 3133);
DISPLAY 0.489362 (-3337 3133);
PAINT GREEN (-3337 3133);
FORCEPROP 2 LAST CDS_LIB mstr_standard
J 0
(-3275 3125);
DISPLAY 0.723404 (-3275 3125);
PAINT MONO (-3275 3125);
DISPLAY INVISIBLE (-3275 3125);
FORCEPROP 1 LAST BODY_TYPE PLUMBING
J 0
(-3275 3175);
DISPLAY 0.872340 (-3275 3175);
PAINT GREEN (-3275 3175);
DISPLAY INVISIBLE (-3275 3175);
FORCEPROP 1 LAST HDL_TAP TRUE
J 0
(-2950 3000);
DISPLAY 0.872340 (-2950 3000);
DISPLAY INVISIBLE (-2950 3000);
FORCEPROP 1 LAST PATH I225
J 0
(-3277 3125);
DISPLAY 0.872340 (-3277 3125);
PAINT GREEN (-3277 3125);
DISPLAY INVISIBLE (-3277 3125);
FORCEADD TAP..1
(-3275 3025);
FORCEPROP 3 LASTPIN (-3325 3025) SIG_NAME M_D_CPU1_SB_DQS_DN<3>
J 0
(-3315 3035);
DISPLAY 0.659574 (-3315 3035);
PAINT MONO (-3315 3035);
DISPLAY INVISIBLE (-3315 3035);
FORCEPROP 1 LASTPIN (-3325 3025) BN 3
J 0
(-3337 3033);
DISPLAY 0.489362 (-3337 3033);
PAINT GREEN (-3337 3033);
FORCEPROP 2 LAST CDS_LIB mstr_standard
J 0
(-3275 3025);
DISPLAY 0.723404 (-3275 3025);
PAINT MONO (-3275 3025);
DISPLAY INVISIBLE (-3275 3025);
FORCEPROP 1 LAST BODY_TYPE PLUMBING
J 0
(-3275 3075);
DISPLAY 0.872340 (-3275 3075);
PAINT GREEN (-3275 3075);
DISPLAY INVISIBLE (-3275 3075);
FORCEPROP 1 LAST HDL_TAP TRUE
J 0
(-2950 2900);
DISPLAY 0.872340 (-2950 2900);
DISPLAY INVISIBLE (-2950 2900);
FORCEPROP 1 LAST PATH I226
J 0
(-3277 3025);
DISPLAY 0.872340 (-3277 3025);
PAINT GREEN (-3277 3025);
DISPLAY INVISIBLE (-3277 3025);
FORCEADD TAP..1
(-3275 2925);
FORCEPROP 3 LASTPIN (-3325 2925) SIG_NAME M_D_CPU1_SB_DQS_DN<2>
J 0
(-3315 2935);
DISPLAY 0.659574 (-3315 2935);
PAINT MONO (-3315 2935);
DISPLAY INVISIBLE (-3315 2935);
FORCEPROP 1 LASTPIN (-3325 2925) BN 2
J 0
(-3337 2933);
DISPLAY 0.489362 (-3337 2933);
PAINT GREEN (-3337 2933);
FORCEPROP 2 LAST CDS_LIB mstr_standard
J 0
(-3275 2925);
DISPLAY 0.723404 (-3275 2925);
PAINT MONO (-3275 2925);
DISPLAY INVISIBLE (-3275 2925);
FORCEPROP 1 LAST BODY_TYPE PLUMBING
J 0
(-3275 2975);
DISPLAY 0.872340 (-3275 2975);
PAINT GREEN (-3275 2975);
DISPLAY INVISIBLE (-3275 2975);
FORCEPROP 1 LAST HDL_TAP TRUE
J 0
(-2950 2800);
DISPLAY 0.872340 (-2950 2800);
DISPLAY INVISIBLE (-2950 2800);
FORCEPROP 1 LAST PATH I227
J 0
(-3277 2925);
DISPLAY 0.872340 (-3277 2925);
PAINT GREEN (-3277 2925);
DISPLAY INVISIBLE (-3277 2925);
FORCEADD TAP..1
(-3275 2825);
FORCEPROP 3 LASTPIN (-3325 2825) SIG_NAME M_D_CPU1_SB_DQS_DN<1>
J 0
(-3315 2835);
DISPLAY 0.659574 (-3315 2835);
PAINT MONO (-3315 2835);
DISPLAY INVISIBLE (-3315 2835);
FORCEPROP 1 LASTPIN (-3325 2825) BN 1
J 0
(-3337 2833);
DISPLAY 0.489362 (-3337 2833);
PAINT GREEN (-3337 2833);
FORCEPROP 2 LAST CDS_LIB mstr_standard
J 0
(-3275 2825);
DISPLAY 0.723404 (-3275 2825);
PAINT MONO (-3275 2825);
DISPLAY INVISIBLE (-3275 2825);
FORCEPROP 1 LAST BODY_TYPE PLUMBING
J 0
(-3275 2875);
DISPLAY 0.872340 (-3275 2875);
PAINT GREEN (-3275 2875);
DISPLAY INVISIBLE (-3275 2875);
FORCEPROP 1 LAST HDL_TAP TRUE
J 0
(-2950 2700);
DISPLAY 0.872340 (-2950 2700);
DISPLAY INVISIBLE (-2950 2700);
FORCEPROP 1 LAST PATH I228
J 0
(-3277 2825);
DISPLAY 0.872340 (-3277 2825);
PAINT GREEN (-3277 2825);
DISPLAY INVISIBLE (-3277 2825);
FORCEADD TAP..1
(-3475 3075);
FORCEPROP 3 LASTPIN (-3525 3075) SIG_NAME M_D_CPU1_SB_DQS_DP<3>
J 0
(-3515 3085);
DISPLAY 0.659574 (-3515 3085);
PAINT MONO (-3515 3085);
DISPLAY INVISIBLE (-3515 3085);
FORCEPROP 1 LASTPIN (-3525 3075) BN 3
J 0
(-3537 3083);
DISPLAY 0.489362 (-3537 3083);
PAINT GREEN (-3537 3083);
FORCEPROP 2 LAST CDS_LIB mstr_standard
J 0
(-3475 3075);
DISPLAY 0.723404 (-3475 3075);
PAINT MONO (-3475 3075);
DISPLAY INVISIBLE (-3475 3075);
FORCEPROP 1 LAST BODY_TYPE PLUMBING
J 0
(-3475 3125);
DISPLAY 0.872340 (-3475 3125);
PAINT GREEN (-3475 3125);
DISPLAY INVISIBLE (-3475 3125);
FORCEPROP 1 LAST HDL_TAP TRUE
J 0
(-3150 2950);
DISPLAY 0.872340 (-3150 2950);
DISPLAY INVISIBLE (-3150 2950);
FORCEPROP 1 LAST PATH I229
J 0
(-3477 3075);
DISPLAY 0.872340 (-3477 3075);
PAINT GREEN (-3477 3075);
DISPLAY INVISIBLE (-3477 3075);
FORCEADD TAP..1
R 2
(-7800 3975);
FORCEPROP 3 LASTPIN (-7750 3975) SIG_NAME M_D_CPU1_SA_CB<3>
J 0
(-7740 3985);
DISPLAY 0.659574 (-7740 3985);
PAINT MONO (-7740 3985);
DISPLAY INVISIBLE (-7740 3985);
FORCEPROP 1 LASTPIN (-7750 3975) BN 3
J 2
(-7738 3983);
DISPLAY 0.489362 (-7738 3983);
PAINT GREEN (-7738 3983);
FORCEPROP 2 LAST CDS_LIB mstr_standard
J 0
(-7800 3975);
DISPLAY 0.723404 (-7800 3975);
PAINT MONO (-7800 3975);
DISPLAY INVISIBLE (-7800 3975);
FORCEPROP 1 LAST BODY_TYPE PLUMBING
J 2
(-7800 4025);
DISPLAY 0.872340 (-7800 4025);
PAINT GREEN (-7800 4025);
DISPLAY INVISIBLE (-7800 4025);
FORCEPROP 1 LAST HDL_TAP TRUE
J 2
(-8125 3850);
DISPLAY 0.872340 (-8125 3850);
DISPLAY INVISIBLE (-8125 3850);
FORCEPROP 1 LAST PATH I23
J 2
(-7798 3975);
DISPLAY 0.872340 (-7798 3975);
PAINT GREEN (-7798 3975);
DISPLAY INVISIBLE (-7798 3975);
FORCEADD TAP..1
(-3475 3275);
FORCEPROP 3 LASTPIN (-3525 3275) SIG_NAME M_D_CPU1_SB_DQS_DP<5>
J 0
(-3515 3285);
DISPLAY 0.659574 (-3515 3285);
PAINT MONO (-3515 3285);
DISPLAY INVISIBLE (-3515 3285);
FORCEPROP 1 LASTPIN (-3525 3275) BN 5
J 0
(-3537 3283);
DISPLAY 0.489362 (-3537 3283);
PAINT GREEN (-3537 3283);
FORCEPROP 2 LAST CDS_LIB mstr_standard
J 0
(-3475 3275);
DISPLAY 0.723404 (-3475 3275);
PAINT MONO (-3475 3275);
DISPLAY INVISIBLE (-3475 3275);
FORCEPROP 1 LAST BODY_TYPE PLUMBING
J 0
(-3475 3325);
DISPLAY 0.872340 (-3475 3325);
PAINT GREEN (-3475 3325);
DISPLAY INVISIBLE (-3475 3325);
FORCEPROP 1 LAST HDL_TAP TRUE
J 0
(-3150 3150);
DISPLAY 0.872340 (-3150 3150);
DISPLAY INVISIBLE (-3150 3150);
FORCEPROP 1 LAST PATH I230
J 0
(-3477 3275);
DISPLAY 0.872340 (-3477 3275);
PAINT GREEN (-3477 3275);
DISPLAY INVISIBLE (-3477 3275);
FORCEADD TAP..1
(-3475 3175);
FORCEPROP 3 LASTPIN (-3525 3175) SIG_NAME M_D_CPU1_SB_DQS_DP<4>
J 0
(-3515 3185);
DISPLAY 0.659574 (-3515 3185);
PAINT MONO (-3515 3185);
DISPLAY INVISIBLE (-3515 3185);
FORCEPROP 1 LASTPIN (-3525 3175) BN 4
J 0
(-3537 3183);
DISPLAY 0.489362 (-3537 3183);
PAINT GREEN (-3537 3183);
FORCEPROP 2 LAST CDS_LIB mstr_standard
J 0
(-3475 3175);
DISPLAY 0.723404 (-3475 3175);
PAINT MONO (-3475 3175);
DISPLAY INVISIBLE (-3475 3175);
FORCEPROP 1 LAST BODY_TYPE PLUMBING
J 0
(-3475 3225);
DISPLAY 0.872340 (-3475 3225);
PAINT GREEN (-3475 3225);
DISPLAY INVISIBLE (-3475 3225);
FORCEPROP 1 LAST HDL_TAP TRUE
J 0
(-3150 3050);
DISPLAY 0.872340 (-3150 3050);
DISPLAY INVISIBLE (-3150 3050);
FORCEPROP 1 LAST PATH I231
J 0
(-3477 3175);
DISPLAY 0.872340 (-3477 3175);
PAINT GREEN (-3477 3175);
DISPLAY INVISIBLE (-3477 3175);
FORCEADD TAP..1
(-3475 2775);
FORCEPROP 3 LASTPIN (-3525 2775) SIG_NAME M_D_CPU1_SB_DQS_DP<0>
J 0
(-3515 2785);
DISPLAY 0.659574 (-3515 2785);
PAINT MONO (-3515 2785);
DISPLAY INVISIBLE (-3515 2785);
FORCEPROP 1 LASTPIN (-3525 2775) BN 0
J 0
(-3537 2783);
DISPLAY 0.489362 (-3537 2783);
PAINT GREEN (-3537 2783);
FORCEPROP 2 LAST CDS_LIB mstr_standard
J 0
(-3475 2775);
DISPLAY 0.723404 (-3475 2775);
PAINT MONO (-3475 2775);
DISPLAY INVISIBLE (-3475 2775);
FORCEPROP 1 LAST BODY_TYPE PLUMBING
J 0
(-3475 2825);
DISPLAY 0.872340 (-3475 2825);
PAINT GREEN (-3475 2825);
DISPLAY INVISIBLE (-3475 2825);
FORCEPROP 1 LAST HDL_TAP TRUE
J 0
(-3150 2650);
DISPLAY 0.872340 (-3150 2650);
DISPLAY INVISIBLE (-3150 2650);
FORCEPROP 1 LAST PATH I232
J 0
(-3477 2775);
DISPLAY 0.872340 (-3477 2775);
PAINT GREEN (-3477 2775);
DISPLAY INVISIBLE (-3477 2775);
FORCEADD TAP..1
(-3475 2875);
FORCEPROP 3 LASTPIN (-3525 2875) SIG_NAME M_D_CPU1_SB_DQS_DP<1>
J 0
(-3515 2885);
DISPLAY 0.659574 (-3515 2885);
PAINT MONO (-3515 2885);
DISPLAY INVISIBLE (-3515 2885);
FORCEPROP 1 LASTPIN (-3525 2875) BN 1
J 0
(-3537 2883);
DISPLAY 0.489362 (-3537 2883);
PAINT GREEN (-3537 2883);
FORCEPROP 2 LAST CDS_LIB mstr_standard
J 0
(-3475 2875);
DISPLAY 0.723404 (-3475 2875);
PAINT MONO (-3475 2875);
DISPLAY INVISIBLE (-3475 2875);
FORCEPROP 1 LAST BODY_TYPE PLUMBING
J 0
(-3475 2925);
DISPLAY 0.872340 (-3475 2925);
PAINT GREEN (-3475 2925);
DISPLAY INVISIBLE (-3475 2925);
FORCEPROP 1 LAST HDL_TAP TRUE
J 0
(-3150 2750);
DISPLAY 0.872340 (-3150 2750);
DISPLAY INVISIBLE (-3150 2750);
FORCEPROP 1 LAST PATH I233
J 0
(-3477 2875);
DISPLAY 0.872340 (-3477 2875);
PAINT GREEN (-3477 2875);
DISPLAY INVISIBLE (-3477 2875);
FORCEADD TAP..1
(-3475 2975);
FORCEPROP 3 LASTPIN (-3525 2975) SIG_NAME M_D_CPU1_SB_DQS_DP<2>
J 0
(-3515 2985);
DISPLAY 0.659574 (-3515 2985);
PAINT MONO (-3515 2985);
DISPLAY INVISIBLE (-3515 2985);
FORCEPROP 1 LASTPIN (-3525 2975) BN 2
J 0
(-3537 2983);
DISPLAY 0.489362 (-3537 2983);
PAINT GREEN (-3537 2983);
FORCEPROP 2 LAST CDS_LIB mstr_standard
J 0
(-3475 2975);
DISPLAY 0.723404 (-3475 2975);
PAINT MONO (-3475 2975);
DISPLAY INVISIBLE (-3475 2975);
FORCEPROP 1 LAST BODY_TYPE PLUMBING
J 0
(-3475 3025);
DISPLAY 0.872340 (-3475 3025);
PAINT GREEN (-3475 3025);
DISPLAY INVISIBLE (-3475 3025);
FORCEPROP 1 LAST HDL_TAP TRUE
J 0
(-3150 2850);
DISPLAY 0.872340 (-3150 2850);
DISPLAY INVISIBLE (-3150 2850);
FORCEPROP 1 LAST PATH I234
J 0
(-3477 2975);
DISPLAY 0.872340 (-3477 2975);
PAINT GREEN (-3477 2975);
DISPLAY INVISIBLE (-3477 2975);
FORCEADD TAP..1
(-3275 2725);
FORCEPROP 3 LASTPIN (-3325 2725) SIG_NAME M_D_CPU1_SB_DQS_DN<0>
J 0
(-3315 2735);
DISPLAY 0.659574 (-3315 2735);
PAINT MONO (-3315 2735);
DISPLAY INVISIBLE (-3315 2735);
FORCEPROP 1 LASTPIN (-3325 2725) BN 0
J 0
(-3337 2733);
DISPLAY 0.489362 (-3337 2733);
PAINT GREEN (-3337 2733);
FORCEPROP 2 LAST CDS_LIB mstr_standard
J 0
(-3275 2725);
DISPLAY 0.723404 (-3275 2725);
PAINT MONO (-3275 2725);
DISPLAY INVISIBLE (-3275 2725);
FORCEPROP 1 LAST BODY_TYPE PLUMBING
J 0
(-3275 2775);
DISPLAY 0.872340 (-3275 2775);
PAINT GREEN (-3275 2775);
DISPLAY INVISIBLE (-3275 2775);
FORCEPROP 1 LAST HDL_TAP TRUE
J 0
(-2950 2600);
DISPLAY 0.872340 (-2950 2600);
DISPLAY INVISIBLE (-2950 2600);
FORCEPROP 1 LAST PATH I235
J 0
(-3277 2725);
DISPLAY 0.872340 (-3277 2725);
PAINT GREEN (-3277 2725);
DISPLAY INVISIBLE (-3277 2725);
FORCEADD SCONN288_DDR506112002KQ..2
(-4425 3725);
FORCEPROP 1 LAST LOCATION J30
J 0
(-5025 5050);
DISPLAY 0.468085 (-5025 5050);
PAINT SKYBLUE (-5025 5050);
FORCEPROP 0 LAST $SEC 2
J 0
(-4875 5200);
DISPLAY 0.680851 (-4875 5200);
PAINT MONO (-4875 5200);
DISPLAY INVISIBLE (-4875 5200);
FORCEPROP 0 LAST CDS_SEC 2
J 0
(-4875 5200);
DISPLAY 1.021277 (-4875 5200);
DISPLAY INVISIBLE (-4875 5200);
FORCEPROP 0 LASTPIN (-3675 3775) $PN 12
J 0
(-3665 3785);
DISPLAY 0.680851 (-3665 3785);
PAINT MONO (-3665 3785);
FORCEPROP 0 LASTPIN (-3675 3825) $PN 11
J 0
(-3665 3835);
DISPLAY 0.680851 (-3665 3835);
PAINT MONO (-3665 3835);
FORCEPROP 0 LASTPIN (-3675 2725) $PN 105
J 0
(-3665 2735);
DISPLAY 0.680851 (-3665 2735);
PAINT MONO (-3665 2735);
FORCEPROP 0 LASTPIN (-3675 2775) $PN 104
J 0
(-3665 2785);
DISPLAY 0.680851 (-3665 2785);
PAINT MONO (-3665 2785);
FORCEPROP 0 LASTPIN (-3675 3875) $PN 23
J 0
(-3665 3885);
DISPLAY 0.680851 (-3665 3885);
PAINT MONO (-3665 3885);
FORCEPROP 0 LASTPIN (-3675 3925) $PN 22
J 0
(-3665 3935);
DISPLAY 0.680851 (-3665 3935);
PAINT MONO (-3665 3935);
FORCEPROP 0 LASTPIN (-3675 2825) $PN 116
J 0
(-3665 2835);
DISPLAY 0.680851 (-3665 2835);
PAINT MONO (-3665 2835);
FORCEPROP 0 LASTPIN (-3675 2875) $PN 115
J 0
(-3665 2885);
DISPLAY 0.680851 (-3665 2885);
PAINT MONO (-3665 2885);
FORCEPROP 0 LASTPIN (-3675 3975) $PN 34
J 0
(-3665 3985);
DISPLAY 0.680851 (-3665 3985);
PAINT MONO (-3665 3985);
FORCEPROP 0 LASTPIN (-3675 4025) $PN 33
J 0
(-3665 4035);
DISPLAY 0.680851 (-3665 4035);
PAINT MONO (-3665 4035);
FORCEPROP 0 LASTPIN (-3675 2925) $PN 127
J 0
(-3665 2935);
DISPLAY 0.680851 (-3665 2935);
PAINT MONO (-3665 2935);
FORCEPROP 0 LASTPIN (-3675 2975) $PN 126
J 0
(-3665 2985);
DISPLAY 0.680851 (-3665 2985);
PAINT MONO (-3665 2985);
FORCEPROP 0 LASTPIN (-3675 4075) $PN 45
J 0
(-3665 4085);
DISPLAY 0.680851 (-3665 4085);
PAINT MONO (-3665 4085);
FORCEPROP 0 LASTPIN (-3675 4125) $PN 44
J 0
(-3665 4135);
DISPLAY 0.680851 (-3665 4135);
PAINT MONO (-3665 4135);
FORCEPROP 0 LASTPIN (-3675 3025) $PN 138
J 0
(-3665 3035);
DISPLAY 0.680851 (-3665 3035);
PAINT MONO (-3665 3035);
FORCEPROP 0 LASTPIN (-3675 3075) $PN 137
J 0
(-3665 3085);
DISPLAY 0.680851 (-3665 3085);
PAINT MONO (-3665 3085);
FORCEPROP 0 LASTPIN (-3675 4175) $PN 56
J 0
(-3665 4185);
DISPLAY 0.680851 (-3665 4185);
PAINT MONO (-3665 4185);
FORCEPROP 0 LASTPIN (-3675 4225) $PN 55
J 0
(-3665 4235);
DISPLAY 0.680851 (-3665 4235);
PAINT MONO (-3665 4235);
FORCEPROP 0 LASTPIN (-3675 3125) $PN 238
J 0
(-3665 3135);
DISPLAY 0.680851 (-3665 3135);
PAINT MONO (-3665 3135);
FORCEPROP 0 LASTPIN (-3675 3175) $PN 239
J 0
(-3665 3185);
DISPLAY 0.680851 (-3665 3185);
PAINT MONO (-3665 3185);
FORCEPROP 0 LASTPIN (-3675 4275) $PN 156
J 0
(-3665 4285);
DISPLAY 0.680851 (-3665 4285);
PAINT MONO (-3665 4285);
FORCEPROP 0 LASTPIN (-3675 4325) $PN 157
J 0
(-3665 4335);
DISPLAY 0.680851 (-3665 4335);
PAINT MONO (-3665 4335);
FORCEPROP 0 LASTPIN (-3675 3225) $PN 249
J 0
(-3665 3235);
DISPLAY 0.680851 (-3665 3235);
PAINT MONO (-3665 3235);
FORCEPROP 0 LASTPIN (-3675 3275) $PN 250
J 0
(-3665 3285);
DISPLAY 0.680851 (-3665 3285);
PAINT MONO (-3665 3285);
FORCEPROP 0 LASTPIN (-3675 4375) $PN 167
J 0
(-3665 4385);
DISPLAY 0.680851 (-3665 4385);
PAINT MONO (-3665 4385);
FORCEPROP 0 LASTPIN (-3675 4425) $PN 168
J 0
(-3665 4435);
DISPLAY 0.680851 (-3665 4435);
PAINT MONO (-3665 4435);
FORCEPROP 0 LASTPIN (-3675 3325) $PN 260
J 0
(-3665 3335);
DISPLAY 0.680851 (-3665 3335);
PAINT MONO (-3665 3335);
FORCEPROP 0 LASTPIN (-3675 3375) $PN 261
J 0
(-3665 3385);
DISPLAY 0.680851 (-3665 3385);
PAINT MONO (-3665 3385);
FORCEPROP 0 LASTPIN (-3675 4475) $PN 178
J 0
(-3665 4485);
DISPLAY 0.680851 (-3665 4485);
PAINT MONO (-3665 4485);
FORCEPROP 0 LASTPIN (-3675 4525) $PN 179
J 0
(-3665 4535);
DISPLAY 0.680851 (-3665 4535);
PAINT MONO (-3665 4535);
FORCEPROP 0 LASTPIN (-3675 3425) $PN 271
J 0
(-3665 3435);
DISPLAY 0.680851 (-3665 3435);
PAINT MONO (-3665 3435);
FORCEPROP 0 LASTPIN (-3675 3475) $PN 272
J 0
(-3665 3485);
DISPLAY 0.680851 (-3665 3485);
PAINT MONO (-3665 3485);
FORCEPROP 0 LASTPIN (-3675 4575) $PN 189
J 0
(-3665 4585);
DISPLAY 0.680851 (-3665 4585);
PAINT MONO (-3665 4585);
FORCEPROP 0 LASTPIN (-3675 4625) $PN 190
J 0
(-3665 4635);
DISPLAY 0.680851 (-3665 4635);
PAINT MONO (-3665 4635);
FORCEPROP 0 LASTPIN (-3675 3525) $PN 282
J 0
(-3665 3535);
DISPLAY 0.680851 (-3665 3535);
PAINT MONO (-3665 3535);
FORCEPROP 0 LASTPIN (-3675 3575) $PN 283
J 0
(-3665 3585);
DISPLAY 0.680851 (-3665 3585);
PAINT MONO (-3665 3585);
FORCEPROP 0 LASTPIN (-3675 4675) $PN 200
J 0
(-3665 4685);
DISPLAY 0.680851 (-3665 4685);
PAINT MONO (-3665 4685);
FORCEPROP 0 LASTPIN (-3675 4725) $PN 201
J 0
(-3665 4735);
DISPLAY 0.680851 (-3665 4735);
PAINT MONO (-3665 4735);
FORCEPROP 0 LASTPIN (-3675 3625) $PN 94
J 0
(-3665 3635);
DISPLAY 0.680851 (-3665 3635);
PAINT MONO (-3665 3635);
FORCEPROP 0 LASTPIN (-3675 3675) $PN 93
J 0
(-3665 3685);
DISPLAY 0.680851 (-3665 3685);
PAINT MONO (-3665 3685);
FORCEPROP 1 LAST MATERIAL IO
J 0
(-5025 4900);
DISPLAY 0.468085 (-5025 4900);
PAINT SKYBLUE (-5025 4900);
FORCEPROP 2 LAST VALUE SCONN288_DDR506112002KQ
J 0
(-4875 5100);
DISPLAY 0.489362 (-4875 5100);
PAINT SKYBLUE (-4875 5100);
FORCEPROP 2 LAST PART_TYPE SMLF
J 0
(-4875 5150);
DISPLAY 1.021277 (-4875 5150);
FORCEPROP 2 LAST CDS_LIB pure_quanta
J 0
(-4425 3725);
DISPLAY INVISIBLE (-4425 3725);
FORCEPROP 1 LAST NEEDS_NO_SIZE TRUE
J 0
(-4425 3725);
DISPLAY 0.723404 (-4425 3725);
PAINT GREEN (-4425 3725);
DISPLAY INVISIBLE (-4425 3725);
FORCEPROP 1 LAST CDS_LMAN_SYM_OUTLINE -600,1150,600,-1150
J 0
(-4425 3725);
DISPLAY 0.468085 (-4425 3725);
PAINT GREEN (-4425 3725);
DISPLAY INVISIBLE (-4425 3725);
FORCEPROP 1 LAST PATH I236
J 0
(-4425 3725);
DISPLAY 0.723404 (-4425 3725);
PAINT GREEN (-4425 3725);
DISPLAY INVISIBLE (-4425 3725);
FORCEPROP 1 LAST PART_NUMBER DFHST8FS479
J 0
(-5025 4975);
DISPLAY 0.468085 (-5025 4975);
PAINT SKYBLUE (-5025 4975);
DISPLAY INVISIBLE (-5025 4975);
FORCEADD GND..1
(-2900 5450);
FORCEPROP 3 LASTPIN (-2900 5500) SIG_NAME GND\g
J 0
(-2890 5510);
DISPLAY 0.659574 (-2890 5510);
PAINT MONO (-2890 5510);
DISPLAY INVISIBLE (-2890 5510);
FORCEPROP 2 LAST ROOM MEM_EFGH_DECOUPLING_CAPS
J 0
(-2875 5525);
DISPLAY 0.659574 (-2875 5525);
PAINT RED (-2875 5525);
DISPLAY INVISIBLE (-2875 5525);
FORCEPROP 1 LAST SIZE 1B
J 0
(-2825 5400);
DISPLAY 0.723404 (-2825 5400);
PAINT GREEN (-2825 5400);
DISPLAY INVISIBLE (-2825 5400);
FORCEPROP 2 LAST BOM_COST MEM
J 0
(-2875 5575);
DISPLAY 0.659574 (-2875 5575);
DISPLAY INVISIBLE (-2875 5575);
FORCEPROP 2 LAST CDS_LIB pure_quanta_power
J 0
(-2900 5450);
DISPLAY INVISIBLE (-2900 5450);
FORCEPROP 1 LAST HDL_POWER GND
J 0
(-2900 5600);
DISPLAY 0.723404 (-2900 5600);
PAINT GREEN (-2900 5600);
DISPLAY INVISIBLE (-2900 5600);
FORCEPROP 1 LAST PATH I237
J 0
(-2825 5450);
DISPLAY 0.872340 (-2825 5450);
PAINT AQUA (-2825 5450);
DISPLAY INVISIBLE (-2825 5450);
FORCEADD Q_CAP..1
R 2
(-2900 5800);
FORCEPROP 1 LAST LOCATION C181
J 2
(-2950 5900);
DISPLAY 0.489362 (-2950 5900);
PAINT SKYBLUE (-2950 5900);
FORCEPROP 0 LAST $SEC 1
J 0
(-2950 5950);
DISPLAY 0.680851 (-2950 5950);
PAINT MONO (-2950 5950);
DISPLAY INVISIBLE (-2950 5950);
FORCEPROP 0 LAST CDS_SEC 1
J 0
(-2950 5950);
DISPLAY 0.680851 (-2950 5950);
DISPLAY INVISIBLE (-2950 5950);
FORCEPROP 1 LASTPIN (-2900 5900) $PN 1
J 2
(-2910 5880);
DISPLAY 0.489362 (-2910 5880);
PAINT MONO (-2910 5880);
FORCEPROP 1 LASTPIN (-2900 5700) $PN 2
J 2
(-2910 5680);
DISPLAY 0.489362 (-2910 5680);
PAINT MONO (-2910 5680);
FORCEPROP 1 LAST MATERIAL X6S
J 2
(-2950 5700);
DISPLAY 0.489362 (-2950 5700);
PAINT SKYBLUE (-2950 5700);
FORCEPROP 1 LAST TOLERANCE 10%
J 2
(-2950 5750);
DISPLAY 0.489362 (-2950 5750);
PAINT SKYBLUE (-2950 5750);
FORCEPROP 1 LAST VALUE 10UF
J 2
(-2950 5850);
DISPLAY 0.489362 (-2950 5850);
PAINT SKYBLUE (-2950 5850);
FORCEPROP 1 LAST VOLTAGE 25V
J 2
(-2950 5800);
DISPLAY 0.489362 (-2950 5800);
PAINT SKYBLUE (-2950 5800);
FORCEPROP 1 LAST PACK_TYPE C0805
J 2
(-2950 5600);
DISPLAY 0.489362 (-2950 5600);
PAINT SKYBLUE (-2950 5600);
FORCEPROP 0 LAST BOM_COST MEM
J 2
(-2955 5945);
DISPLAY 0.595745 (-2955 5945);
PAINT MONO (-2955 5945);
DISPLAY INVISIBLE (-2955 5945);
FORCEPROP 2 LAST CDS_LIB pure_quanta
J 0
(-2900 5800);
DISPLAY INVISIBLE (-2900 5800);
FORCEPROP 2 LAST ROOM 
J 2
(-2955 5945);
DISPLAY 0.595745 (-2955 5945);
PAINT RED (-2955 5945);
DISPLAY INVISIBLE (-2955 5945);
FORCEPROP 1 LAST PATH I238
J 2
(-2950 5950);
DISPLAY 0.978723 (-2950 5950);
PAINT WHITE (-2950 5950);
DISPLAY INVISIBLE (-2950 5950);
FORCEPROP 1 LAST PART_NUMBER CH6104KEA00
J 2
(-2950 5650);
DISPLAY 0.489362 (-2950 5650);
PAINT SKYBLUE (-2950 5650);
DISPLAY INVISIBLE (-2950 5650);
FORCEADD Q_CAP..1
R 2
(-2325 5800);
FORCEPROP 1 LAST LOCATION C182
J 2
(-2375 5900);
DISPLAY 0.489362 (-2375 5900);
PAINT SKYBLUE (-2375 5900);
FORCEPROP 0 LAST $SEC 1
J 0
(-2375 5950);
DISPLAY 0.680851 (-2375 5950);
PAINT MONO (-2375 5950);
DISPLAY INVISIBLE (-2375 5950);
FORCEPROP 0 LAST CDS_SEC 1
J 0
(-2375 5950);
DISPLAY 0.680851 (-2375 5950);
DISPLAY INVISIBLE (-2375 5950);
FORCEPROP 1 LASTPIN (-2325 5900) $PN 1
J 2
(-2335 5880);
DISPLAY 0.489362 (-2335 5880);
PAINT MONO (-2335 5880);
FORCEPROP 1 LASTPIN (-2325 5700) $PN 2
J 2
(-2335 5680);
DISPLAY 0.489362 (-2335 5680);
PAINT MONO (-2335 5680);
FORCEPROP 1 LAST MATERIAL X6S
J 2
(-2375 5700);
DISPLAY 0.489362 (-2375 5700);
PAINT SKYBLUE (-2375 5700);
FORCEPROP 1 LAST TOLERANCE 10%
J 2
(-2375 5750);
DISPLAY 0.489362 (-2375 5750);
PAINT SKYBLUE (-2375 5750);
FORCEPROP 1 LAST VALUE 10UF
J 2
(-2375 5850);
DISPLAY 0.489362 (-2375 5850);
PAINT SKYBLUE (-2375 5850);
FORCEPROP 1 LAST VOLTAGE 25V
J 2
(-2375 5800);
DISPLAY 0.489362 (-2375 5800);
PAINT SKYBLUE (-2375 5800);
FORCEPROP 1 LAST PACK_TYPE C0805
J 2
(-2375 5600);
DISPLAY 0.489362 (-2375 5600);
PAINT SKYBLUE (-2375 5600);
FORCEPROP 0 LAST BOM_COST MEM
J 2
(-2380 5945);
DISPLAY 0.595745 (-2380 5945);
PAINT MONO (-2380 5945);
DISPLAY INVISIBLE (-2380 5945);
FORCEPROP 2 LAST CDS_LIB pure_quanta
J 0
(-2325 5800);
DISPLAY INVISIBLE (-2325 5800);
FORCEPROP 2 LAST ROOM 
J 2
(-2380 5945);
DISPLAY 0.595745 (-2380 5945);
PAINT RED (-2380 5945);
DISPLAY INVISIBLE (-2380 5945);
FORCEPROP 1 LAST PATH I239
J 2
(-2375 5950);
DISPLAY 0.978723 (-2375 5950);
PAINT WHITE (-2375 5950);
DISPLAY INVISIBLE (-2375 5950);
FORCEPROP 1 LAST PART_NUMBER CH6104KEA00
J 2
(-2375 5650);
DISPLAY 0.489362 (-2375 5650);
PAINT SKYBLUE (-2375 5650);
DISPLAY INVISIBLE (-2375 5650);
FORCEADD TAP..1
R 2
(-7800 4025);
FORCEPROP 3 LASTPIN (-7750 4025) SIG_NAME M_D_CPU1_SA_CB<4>
J 0
(-7740 4035);
DISPLAY 0.659574 (-7740 4035);
PAINT MONO (-7740 4035);
DISPLAY INVISIBLE (-7740 4035);
FORCEPROP 1 LASTPIN (-7750 4025) BN 4
J 2
(-7738 4033);
DISPLAY 0.489362 (-7738 4033);
PAINT GREEN (-7738 4033);
FORCEPROP 2 LAST CDS_LIB mstr_standard
J 0
(-7800 4025);
DISPLAY 0.723404 (-7800 4025);
PAINT MONO (-7800 4025);
DISPLAY INVISIBLE (-7800 4025);
FORCEPROP 1 LAST BODY_TYPE PLUMBING
J 2
(-7800 4075);
DISPLAY 0.872340 (-7800 4075);
PAINT GREEN (-7800 4075);
DISPLAY INVISIBLE (-7800 4075);
FORCEPROP 1 LAST HDL_TAP TRUE
J 2
(-8125 3900);
DISPLAY 0.872340 (-8125 3900);
DISPLAY INVISIBLE (-8125 3900);
FORCEPROP 1 LAST PATH I24
J 2
(-7798 4025);
DISPLAY 0.872340 (-7798 4025);
PAINT GREEN (-7798 4025);
DISPLAY INVISIBLE (-7798 4025);
FORCEADD UNIVERSAL_POWER..1
(-2900 6125);
FORCEPROP 3 LASTPIN (-2900 6075) SIG_NAME P12V_MEM_CPU1\g
J 0
(-2890 6085);
DISPLAY 0.659574 (-2890 6085);
PAINT MONO (-2890 6085);
DISPLAY INVISIBLE (-2890 6085);
FORCEPROP 1 LAST HDL_POWER P12V_MEM_CPU1
J 1
(-2900 6175);
DISPLAY 0.489362 (-2900 6175);
PAINT GREEN (-2900 6175);
FORCEPROP 2 LAST CDS_LIB pure_quanta_power
J 0
(-2900 6125);
DISPLAY INVISIBLE (-2900 6125);
FORCEPROP 1 LAST PATH I240
J 0
(-2850 6150);
DISPLAY 0.872340 (-2850 6150);
PAINT AQUA (-2850 6150);
DISPLAY INVISIBLE (-2850 6150);
FORCEADD OFFPAGE..1
(-8475 2800);
FORCEPROP 2 LAST $XR5 103 
J 0
(-9297 2800);
DISPLAY 0.638298 (-9297 2800);
PAINT MONO (-9297 2800);
FORCEPROP 2 LAST $XR4 102 
J 0
(-9177 2800);
DISPLAY 0.638298 (-9177 2800);
PAINT MONO (-9177 2800);
FORCEPROP 2 LAST $XR3 100 
J 0
(-9057 2800);
DISPLAY 0.638298 (-9057 2800);
PAINT MONO (-9057 2800);
FORCEPROP 2 LAST $XR2 99 
J 0
(-8937 2800);
DISPLAY 0.638298 (-8937 2800);
PAINT MONO (-8937 2800);
FORCEPROP 2 LAST $XR1 98 
J 0
(-8847 2800);
DISPLAY 0.638298 (-8847 2800);
PAINT MONO (-8847 2800);
FORCEPROP 2 LAST $XR0 159 
J 0
(-8757 2800);
DISPLAY 0.638298 (-8757 2800);
PAINT MONO (-8757 2800);
FORCEPROP 2 LAST CDS_LIB mstr_standard
J 0
(-8475 2800);
DISPLAY 0.808511 (-8475 2800);
DISPLAY INVISIBLE (-8475 2800);
FORCEPROP 1 LAST OFFPAGE TRUE
J 0
(-8150 2675);
DISPLAY 0.872340 (-8150 2675);
PAINT GREEN (-8150 2675);
DISPLAY INVISIBLE (-8150 2675);
FORCEPROP 1 LAST COMMENT_BODY TRUE
J 0
(-8350 2700);
DISPLAY 0.872340 (-8350 2700);
PAINT GREEN (-8350 2700);
DISPLAY INVISIBLE (-8350 2700);
FORCEPROP 2 LAST PATH I241
J 0
(-8750 2850);
DISPLAY 0.680851 (-8750 2850);
DISPLAY INVISIBLE (-8750 2850);
FORCEADD Q_RES..1
(-7850 2800);
FORCEPROP 1 LAST LOCATION R1583
J 0
(-7900 2825);
DISPLAY 0.510638 (-7900 2825);
PAINT SKYBLUE (-7900 2825);
FORCEPROP 0 LAST $SEC 1
J 0
(-7900 2900);
DISPLAY 0.680851 (-7900 2900);
PAINT MONO (-7900 2900);
DISPLAY INVISIBLE (-7900 2900);
FORCEPROP 0 LAST CDS_SEC 1
J 0
(-7900 2900);
DISPLAY 0.680851 (-7900 2900);
DISPLAY INVISIBLE (-7900 2900);
FORCEPROP 1 LASTPIN (-7950 2800) $PN 1
J 0
(-7938 2812);
DISPLAY 0.787234 (-7938 2812);
PAINT MONO (-7938 2812);
FORCEPROP 1 LASTPIN (-7750 2800) $PN 2
J 0
(-7788 2812);
DISPLAY 0.787234 (-7788 2812);
PAINT MONO (-7788 2812);
FORCEPROP 1 LAST VALUE 49.9
J 2
(-7700 2850);
DISPLAY 0.510638 (-7700 2850);
PAINT SKYBLUE (-7700 2850);
FORCEPROP 1 LAST TOLERANCE 1%
J 0
(-7850 2700);
DISPLAY 0.978723 (-7850 2700);
DISPLAY INVISIBLE (-7850 2700);
FORCEPROP 1 LAST WATTAGE 1/16W
J 2
(-7875 2650);
DISPLAY 0.978723 (-7875 2650);
DISPLAY INVISIBLE (-7875 2650);
FORCEPROP 1 LAST PACK_TYPE 0402LF
J 0
(-7600 2650);
DISPLAY 0.978723 (-7600 2650);
DISPLAY INVISIBLE (-7600 2650);
FORCEPROP 1 LAST MATERIAL CHIP
J 0
(-7850 2650);
DISPLAY 0.978723 (-7850 2650);
DISPLAY INVISIBLE (-7850 2650);
FORCEPROP 2 LAST CDS_LIB pure_quanta
J 0
(-7850 2800);
DISPLAY INVISIBLE (-7850 2800);
FORCEPROP 1 LAST PATH I242
J 0
(-7900 2950);
DISPLAY 0.978723 (-7900 2950);
PAINT WHITE (-7900 2950);
DISPLAY INVISIBLE (-7900 2950);
FORCEPROP 1 LAST PART_NUMBER CS04992FB07
J 0
(-7900 2900);
DISPLAY 0.978723 (-7900 2900);
DISPLAY INVISIBLE (-7900 2900);
FORCEADD Q_RES..1
(-8225 3025);
FORCEPROP 1 LAST LOCATION R1699
J 0
(-8425 3025);
DISPLAY 0.638298 (-8425 3025);
FORCEPROP 0 LAST $SEC 1
J 0
(-8375 3075);
DISPLAY 0.680851 (-8375 3075);
PAINT MONO (-8375 3075);
DISPLAY INVISIBLE (-8375 3075);
FORCEPROP 0 LAST CDS_SEC 1
J 0
(-8375 3075);
DISPLAY 0.680851 (-8375 3075);
DISPLAY INVISIBLE (-8375 3075);
FORCEPROP 1 LASTPIN (-8325 3025) $PN 1
J 0
(-8313 3037);
DISPLAY 0.787234 (-8313 3037);
PAINT MONO (-8313 3037);
FORCEPROP 1 LASTPIN (-8125 3025) $PN 2
J 0
(-8163 3037);
DISPLAY 0.787234 (-8163 3037);
PAINT MONO (-8163 3037);
FORCEPROP 1 LAST MATERIAL CHIP
J 0
(-8325 3000);
DISPLAY 0.404255 (-8325 3000);
FORCEPROP 1 LAST PACK_TYPE 0402LF
J 0
(-8175 3000);
DISPLAY 0.404255 (-8175 3000);
FORCEPROP 1 LAST VALUE 10
J 2
(-8075 3025);
DISPLAY 0.404255 (-8075 3025);
FORCEPROP 1 LAST TOLERANCE 1%
J 0
(-8225 2925);
DISPLAY 0.978723 (-8225 2925);
DISPLAY INVISIBLE (-8225 2925);
FORCEPROP 1 LAST WATTAGE 1/16W
J 2
(-8250 2875);
DISPLAY 0.978723 (-8250 2875);
DISPLAY INVISIBLE (-8250 2875);
FORCEPROP 2 LAST CDS_LIB pure_quanta
J 0
(-8225 3025);
DISPLAY INVISIBLE (-8225 3025);
FORCEPROP 1 LAST PATH I243
J 0
(-8275 3175);
DISPLAY 0.978723 (-8275 3175);
PAINT WHITE (-8275 3175);
DISPLAY INVISIBLE (-8275 3175);
FORCEPROP 1 LAST PART_NUMBER CS01002FB07
J 0
(-8275 3125);
DISPLAY 0.978723 (-8275 3125);
DISPLAY INVISIBLE (-8275 3125);
FORCEADD OFFPAGE..6
(-8900 2900);
FORCEPROP 2 LAST $XR5 159 
J 0
(-9149 2936);
DISPLAY 0.638298 (-9149 2936);
PAINT MONO (-9149 2936);
FORCEPROP 2 LAST $XR4 103 
J 0
(-9359 2864);
DISPLAY 0.638298 (-9359 2864);
PAINT MONO (-9359 2864);
FORCEPROP 2 LAST $XR3 102 
J 0
(-9239 2864);
DISPLAY 0.638298 (-9239 2864);
PAINT MONO (-9239 2864);
FORCEPROP 2 LAST $XR2 100 
J 0
(-9359 2900);
DISPLAY 0.638298 (-9359 2900);
PAINT MONO (-9359 2900);
FORCEPROP 2 LAST $XR1 99 
J 0
(-9239 2900);
DISPLAY 0.638298 (-9239 2900);
PAINT MONO (-9239 2900);
FORCEPROP 2 LAST $XR0 98 
J 0
(-9149 2900);
DISPLAY 0.638298 (-9149 2900);
PAINT MONO (-9149 2900);
FORCEPROP 2 LAST CDS_LIB mstr_standard
J 0
(-8900 2900);
DISPLAY 0.808511 (-8900 2900);
DISPLAY INVISIBLE (-8900 2900);
FORCEPROP 1 LAST OFFPAGE TRUE
J 0
(-8575 2775);
DISPLAY 0.872340 (-8575 2775);
PAINT GREEN (-8575 2775);
DISPLAY INVISIBLE (-8575 2775);
FORCEPROP 1 LAST COMMENT_BODY TRUE
J 0
(-8800 2825);
DISPLAY 0.872340 (-8800 2825);
PAINT GREEN (-8800 2825);
DISPLAY INVISIBLE (-8800 2825);
FORCEPROP 2 LAST PATH I244
J 0
(-9125 2950);
DISPLAY 0.680851 (-9125 2950);
DISPLAY INVISIBLE (-9125 2950);
FORCEADD TAP..1
R 2
(-7800 4125);
FORCEPROP 3 LASTPIN (-7750 4125) SIG_NAME M_D_CPU1_SA_CB<6>
J 0
(-7740 4135);
DISPLAY 0.659574 (-7740 4135);
PAINT MONO (-7740 4135);
DISPLAY INVISIBLE (-7740 4135);
FORCEPROP 1 LASTPIN (-7750 4125) BN 6
J 2
(-7738 4133);
DISPLAY 0.489362 (-7738 4133);
PAINT GREEN (-7738 4133);
FORCEPROP 2 LAST CDS_LIB mstr_standard
J 0
(-7800 4125);
DISPLAY 0.723404 (-7800 4125);
PAINT MONO (-7800 4125);
DISPLAY INVISIBLE (-7800 4125);
FORCEPROP 1 LAST BODY_TYPE PLUMBING
J 2
(-7800 4175);
DISPLAY 0.872340 (-7800 4175);
PAINT GREEN (-7800 4175);
DISPLAY INVISIBLE (-7800 4175);
FORCEPROP 1 LAST HDL_TAP TRUE
J 2
(-8125 4000);
DISPLAY 0.872340 (-8125 4000);
DISPLAY INVISIBLE (-8125 4000);
FORCEPROP 1 LAST PATH I25
J 2
(-7798 4125);
DISPLAY 0.872340 (-7798 4125);
PAINT GREEN (-7798 4125);
DISPLAY INVISIBLE (-7798 4125);
FORCEADD TAP..1
R 2
(-7800 4075);
FORCEPROP 3 LASTPIN (-7750 4075) SIG_NAME M_D_CPU1_SA_CB<5>
J 0
(-7740 4085);
DISPLAY 0.659574 (-7740 4085);
PAINT MONO (-7740 4085);
DISPLAY INVISIBLE (-7740 4085);
FORCEPROP 1 LASTPIN (-7750 4075) BN 5
J 2
(-7738 4083);
DISPLAY 0.489362 (-7738 4083);
PAINT GREEN (-7738 4083);
FORCEPROP 2 LAST CDS_LIB mstr_standard
J 0
(-7800 4075);
DISPLAY 0.723404 (-7800 4075);
PAINT MONO (-7800 4075);
DISPLAY INVISIBLE (-7800 4075);
FORCEPROP 1 LAST BODY_TYPE PLUMBING
J 2
(-7800 4125);
DISPLAY 0.872340 (-7800 4125);
PAINT GREEN (-7800 4125);
DISPLAY INVISIBLE (-7800 4125);
FORCEPROP 1 LAST HDL_TAP TRUE
J 2
(-8125 3950);
DISPLAY 0.872340 (-8125 3950);
DISPLAY INVISIBLE (-8125 3950);
FORCEPROP 1 LAST PATH I26
J 2
(-7798 4075);
DISPLAY 0.872340 (-7798 4075);
PAINT GREEN (-7798 4075);
DISPLAY INVISIBLE (-7798 4075);
FORCEADD TAP..1
R 2
(-7800 4175);
FORCEPROP 3 LASTPIN (-7750 4175) SIG_NAME M_D_CPU1_SA_CB<7>
J 0
(-7740 4185);
DISPLAY 0.659574 (-7740 4185);
PAINT MONO (-7740 4185);
DISPLAY INVISIBLE (-7740 4185);
FORCEPROP 1 LASTPIN (-7750 4175) BN 7
J 2
(-7738 4183);
DISPLAY 0.489362 (-7738 4183);
PAINT GREEN (-7738 4183);
FORCEPROP 2 LAST CDS_LIB mstr_standard
J 0
(-7800 4175);
DISPLAY 0.723404 (-7800 4175);
PAINT MONO (-7800 4175);
DISPLAY INVISIBLE (-7800 4175);
FORCEPROP 1 LAST BODY_TYPE PLUMBING
J 2
(-7800 4225);
DISPLAY 0.872340 (-7800 4225);
PAINT GREEN (-7800 4225);
DISPLAY INVISIBLE (-7800 4225);
FORCEPROP 1 LAST HDL_TAP TRUE
J 2
(-8125 4050);
DISPLAY 0.872340 (-8125 4050);
DISPLAY INVISIBLE (-8125 4050);
FORCEPROP 1 LAST PATH I27
J 2
(-7798 4175);
DISPLAY 0.872340 (-7798 4175);
PAINT GREEN (-7798 4175);
DISPLAY INVISIBLE (-7798 4175);
FORCEADD OFFPAGE..1
(-8400 4325);
FORCEPROP 2 LAST $XR0 40 
J 0
(-8621 4325);
DISPLAY 0.638298 (-8621 4325);
PAINT MONO (-8621 4325);
FORCEPROP 2 LAST CDS_LIB mstr_standard
J 0
(-8400 4325);
DISPLAY 0.723404 (-8400 4325);
PAINT MONO (-8400 4325);
DISPLAY INVISIBLE (-8400 4325);
FORCEPROP 1 LAST OFFPAGE TRUE
J 0
(-8075 4200);
DISPLAY 0.872340 (-8075 4200);
PAINT GREEN (-8075 4200);
DISPLAY INVISIBLE (-8075 4200);
FORCEPROP 1 LAST COMMENT_BODY TRUE
J 0
(-8275 4225);
DISPLAY 0.872340 (-8275 4225);
PAINT GREEN (-8275 4225);
DISPLAY INVISIBLE (-8275 4225);
FORCEPROP 2 LAST PATH I28
J 0
(-8650 4375);
DISPLAY 1.021277 (-8650 4375);
DISPLAY INVISIBLE (-8650 4375);
FORCEADD OFFPAGE..1
(-8400 4275);
FORCEPROP 2 LAST $XR0 40 
J 0
(-8621 4275);
DISPLAY 0.638298 (-8621 4275);
PAINT MONO (-8621 4275);
FORCEPROP 2 LAST CDS_LIB mstr_standard
J 0
(-8400 4275);
DISPLAY 0.808511 (-8400 4275);
DISPLAY INVISIBLE (-8400 4275);
FORCEPROP 1 LAST OFFPAGE TRUE
J 0
(-8075 4150);
DISPLAY 0.872340 (-8075 4150);
PAINT GREEN (-8075 4150);
DISPLAY INVISIBLE (-8075 4150);
FORCEPROP 1 LAST COMMENT_BODY TRUE
J 0
(-8275 4175);
DISPLAY 0.872340 (-8275 4175);
PAINT GREEN (-8275 4175);
DISPLAY INVISIBLE (-8275 4175);
FORCEPROP 2 LAST PATH I29
J 0
(-8650 4325);
DISPLAY 1.021277 (-8650 4325);
DISPLAY INVISIBLE (-8650 4325);
FORCEADD OFFPAGE..1
(-8400 4425);
FORCEPROP 2 LAST $XR0 40 
J 0
(-8621 4425);
DISPLAY 0.638298 (-8621 4425);
PAINT MONO (-8621 4425);
FORCEPROP 2 LAST CDS_LIB mstr_standard
J 0
(-8400 4425);
DISPLAY 0.808511 (-8400 4425);
DISPLAY INVISIBLE (-8400 4425);
FORCEPROP 1 LAST OFFPAGE TRUE
J 0
(-8075 4300);
DISPLAY 0.872340 (-8075 4300);
PAINT GREEN (-8075 4300);
DISPLAY INVISIBLE (-8075 4300);
FORCEPROP 1 LAST COMMENT_BODY TRUE
J 0
(-8275 4325);
DISPLAY 0.872340 (-8275 4325);
PAINT GREEN (-8275 4325);
DISPLAY INVISIBLE (-8275 4325);
FORCEPROP 2 LAST PATH I30
J 0
(-8650 4475);
DISPLAY 1.021277 (-8650 4475);
DISPLAY INVISIBLE (-8650 4475);
FORCEADD OFFPAGE..1
(-8400 4475);
FORCEPROP 2 LAST $XR0 40 
J 0
(-8621 4475);
DISPLAY 0.638298 (-8621 4475);
PAINT MONO (-8621 4475);
FORCEPROP 2 LAST CDS_LIB mstr_standard
J 0
(-8400 4475);
DISPLAY 0.723404 (-8400 4475);
PAINT MONO (-8400 4475);
DISPLAY INVISIBLE (-8400 4475);
FORCEPROP 1 LAST OFFPAGE TRUE
J 0
(-8075 4350);
DISPLAY 0.872340 (-8075 4350);
PAINT GREEN (-8075 4350);
DISPLAY INVISIBLE (-8075 4350);
FORCEPROP 1 LAST COMMENT_BODY TRUE
J 0
(-8275 4375);
DISPLAY 0.872340 (-8275 4375);
PAINT GREEN (-8275 4375);
DISPLAY INVISIBLE (-8275 4375);
FORCEPROP 2 LAST PATH I31
J 0
(-8650 4525);
DISPLAY 1.021277 (-8650 4525);
DISPLAY INVISIBLE (-8650 4525);
FORCEADD OFFPAGE..1
(-8400 4625);
FORCEPROP 2 LAST $XR0 40 
J 0
(-8621 4625);
DISPLAY 0.638298 (-8621 4625);
PAINT MONO (-8621 4625);
FORCEPROP 2 LAST CDS_LIB mstr_standard
J 0
(-8400 4625);
DISPLAY 0.723404 (-8400 4625);
PAINT MONO (-8400 4625);
DISPLAY INVISIBLE (-8400 4625);
FORCEPROP 1 LAST OFFPAGE TRUE
J 0
(-8075 4500);
DISPLAY 0.872340 (-8075 4500);
PAINT GREEN (-8075 4500);
DISPLAY INVISIBLE (-8075 4500);
FORCEPROP 1 LAST COMMENT_BODY TRUE
J 0
(-8275 4525);
DISPLAY 0.872340 (-8275 4525);
PAINT GREEN (-8275 4525);
DISPLAY INVISIBLE (-8275 4525);
FORCEPROP 2 LAST PATH I32
J 0
(-8650 4675);
DISPLAY 1.021277 (-8650 4675);
DISPLAY INVISIBLE (-8650 4675);
FORCEADD OFFPAGE..1
(-8400 4575);
FORCEPROP 2 LAST $XR0 40 
J 0
(-8621 4575);
DISPLAY 0.638298 (-8621 4575);
PAINT MONO (-8621 4575);
FORCEPROP 2 LAST CDS_LIB mstr_standard
J 0
(-8400 4575);
DISPLAY 0.808511 (-8400 4575);
DISPLAY INVISIBLE (-8400 4575);
FORCEPROP 1 LAST OFFPAGE TRUE
J 0
(-8075 4450);
DISPLAY 0.872340 (-8075 4450);
PAINT GREEN (-8075 4450);
DISPLAY INVISIBLE (-8075 4450);
FORCEPROP 1 LAST COMMENT_BODY TRUE
J 0
(-8275 4475);
DISPLAY 0.872340 (-8275 4475);
PAINT GREEN (-8275 4475);
DISPLAY INVISIBLE (-8275 4475);
FORCEPROP 2 LAST PATH I33
J 0
(-8650 4625);
DISPLAY 1.021277 (-8650 4625);
DISPLAY INVISIBLE (-8650 4625);
FORCEADD OFFPAGE..1
(-8400 4725);
FORCEPROP 2 LAST $XR0 40 
J 0
(-8621 4725);
DISPLAY 0.638298 (-8621 4725);
PAINT MONO (-8621 4725);
FORCEPROP 2 LAST CDS_LIB mstr_standard
J 0
(-8400 4725);
DISPLAY 0.808511 (-8400 4725);
DISPLAY INVISIBLE (-8400 4725);
FORCEPROP 1 LAST OFFPAGE TRUE
J 0
(-8075 4600);
DISPLAY 0.872340 (-8075 4600);
PAINT GREEN (-8075 4600);
DISPLAY INVISIBLE (-8075 4600);
FORCEPROP 1 LAST COMMENT_BODY TRUE
J 0
(-8275 4625);
DISPLAY 0.872340 (-8275 4625);
PAINT GREEN (-8275 4625);
DISPLAY INVISIBLE (-8275 4625);
FORCEPROP 2 LAST PATH I34
J 0
(-8650 4775);
DISPLAY 1.021277 (-8650 4775);
DISPLAY INVISIBLE (-8650 4775);
FORCEADD OFFPAGE..1
(-8400 4775);
FORCEPROP 2 LAST $XR0 40 
J 0
(-8621 4775);
DISPLAY 0.638298 (-8621 4775);
PAINT MONO (-8621 4775);
FORCEPROP 2 LAST CDS_LIB mstr_standard
J 0
(-8400 4775);
DISPLAY 0.723404 (-8400 4775);
PAINT MONO (-8400 4775);
DISPLAY INVISIBLE (-8400 4775);
FORCEPROP 1 LAST OFFPAGE TRUE
J 0
(-8075 4650);
DISPLAY 0.872340 (-8075 4650);
PAINT GREEN (-8075 4650);
DISPLAY INVISIBLE (-8075 4650);
FORCEPROP 1 LAST COMMENT_BODY TRUE
J 0
(-8275 4675);
DISPLAY 0.872340 (-8275 4675);
PAINT GREEN (-8275 4675);
DISPLAY INVISIBLE (-8275 4675);
FORCEPROP 2 LAST PATH I35
J 0
(-8650 4825);
DISPLAY 1.021277 (-8650 4825);
DISPLAY INVISIBLE (-8650 4825);
FORCEADD OFFPAGE..1
(-8400 5225);
FORCEPROP 2 LAST $XR0 40 
J 0
(-8621 5225);
DISPLAY 0.638298 (-8621 5225);
PAINT MONO (-8621 5225);
FORCEPROP 2 LAST CDS_LIB mstr_standard
J 0
(-8400 5225);
DISPLAY 0.723404 (-8400 5225);
PAINT MONO (-8400 5225);
DISPLAY INVISIBLE (-8400 5225);
FORCEPROP 1 LAST OFFPAGE TRUE
J 0
(-8075 5100);
DISPLAY 0.872340 (-8075 5100);
PAINT GREEN (-8075 5100);
DISPLAY INVISIBLE (-8075 5100);
FORCEPROP 1 LAST COMMENT_BODY TRUE
J 0
(-8275 5125);
DISPLAY 0.872340 (-8275 5125);
PAINT GREEN (-8275 5125);
DISPLAY INVISIBLE (-8275 5125);
FORCEPROP 2 LAST PATH I36
J 0
(-8650 5275);
DISPLAY 1.021277 (-8650 5275);
DISPLAY INVISIBLE (-8650 5275);
FORCEADD TAP..1
R 2
(-7800 4875);
FORCEPROP 3 LASTPIN (-7750 4875) SIG_NAME M_D_CPU1_SB_CA<0>
J 0
(-7740 4885);
DISPLAY 0.659574 (-7740 4885);
PAINT MONO (-7740 4885);
DISPLAY INVISIBLE (-7740 4885);
FORCEPROP 1 LASTPIN (-7750 4875) BN 0
J 2
(-7738 4883);
DISPLAY 0.489362 (-7738 4883);
PAINT GREEN (-7738 4883);
FORCEPROP 2 LAST CDS_LIB mstr_standard
J 0
(-7800 4875);
DISPLAY 0.723404 (-7800 4875);
PAINT MONO (-7800 4875);
DISPLAY INVISIBLE (-7800 4875);
FORCEPROP 1 LAST BODY_TYPE PLUMBING
J 2
(-7800 4925);
DISPLAY 0.872340 (-7800 4925);
PAINT GREEN (-7800 4925);
DISPLAY INVISIBLE (-7800 4925);
FORCEPROP 1 LAST HDL_TAP TRUE
J 2
(-8125 4750);
DISPLAY 0.872340 (-8125 4750);
DISPLAY INVISIBLE (-8125 4750);
FORCEPROP 1 LAST PATH I37
J 2
(-7798 4875);
DISPLAY 0.872340 (-7798 4875);
PAINT GREEN (-7798 4875);
DISPLAY INVISIBLE (-7798 4875);
FORCEADD TAP..1
R 2
(-7800 4925);
FORCEPROP 3 LASTPIN (-7750 4925) SIG_NAME M_D_CPU1_SB_CA<1>
J 0
(-7740 4935);
DISPLAY 0.659574 (-7740 4935);
PAINT MONO (-7740 4935);
DISPLAY INVISIBLE (-7740 4935);
FORCEPROP 1 LASTPIN (-7750 4925) BN 1
J 2
(-7738 4933);
DISPLAY 0.489362 (-7738 4933);
PAINT GREEN (-7738 4933);
FORCEPROP 2 LAST CDS_LIB mstr_standard
J 0
(-7800 4925);
DISPLAY 0.723404 (-7800 4925);
PAINT MONO (-7800 4925);
DISPLAY INVISIBLE (-7800 4925);
FORCEPROP 1 LAST BODY_TYPE PLUMBING
J 2
(-7800 4975);
DISPLAY 0.872340 (-7800 4975);
PAINT GREEN (-7800 4975);
DISPLAY INVISIBLE (-7800 4975);
FORCEPROP 1 LAST HDL_TAP TRUE
J 2
(-8125 4800);
DISPLAY 0.872340 (-8125 4800);
DISPLAY INVISIBLE (-8125 4800);
FORCEPROP 1 LAST PATH I38
J 2
(-7798 4925);
DISPLAY 0.872340 (-7798 4925);
PAINT GREEN (-7798 4925);
DISPLAY INVISIBLE (-7798 4925);
FORCEADD TAP..1
R 2
(-7800 4975);
FORCEPROP 3 LASTPIN (-7750 4975) SIG_NAME M_D_CPU1_SB_CA<2>
J 0
(-7740 4985);
DISPLAY 0.659574 (-7740 4985);
PAINT MONO (-7740 4985);
DISPLAY INVISIBLE (-7740 4985);
FORCEPROP 1 LASTPIN (-7750 4975) BN 2
J 2
(-7738 4983);
DISPLAY 0.489362 (-7738 4983);
PAINT GREEN (-7738 4983);
FORCEPROP 2 LAST CDS_LIB mstr_standard
J 0
(-7800 4975);
DISPLAY 0.723404 (-7800 4975);
PAINT MONO (-7800 4975);
DISPLAY INVISIBLE (-7800 4975);
FORCEPROP 1 LAST BODY_TYPE PLUMBING
J 2
(-7800 5025);
DISPLAY 0.872340 (-7800 5025);
PAINT GREEN (-7800 5025);
DISPLAY INVISIBLE (-7800 5025);
FORCEPROP 1 LAST HDL_TAP TRUE
J 2
(-8125 4850);
DISPLAY 0.872340 (-8125 4850);
DISPLAY INVISIBLE (-8125 4850);
FORCEPROP 1 LAST PATH I39
J 2
(-7798 4975);
DISPLAY 0.872340 (-7798 4975);
PAINT GREEN (-7798 4975);
DISPLAY INVISIBLE (-7798 4975);
FORCEADD OFFPAGE..1
(-8775 3075);
FORCEPROP 2 LAST $XR0 101 
J 0
(-9027 3075);
DISPLAY 0.638298 (-9027 3075);
PAINT MONO (-9027 3075);
FORCEPROP 2 LAST CDS_LIB mstr_standard
J 0
(-8775 3075);
DISPLAY 0.808511 (-8775 3075);
DISPLAY INVISIBLE (-8775 3075);
FORCEPROP 1 LAST OFFPAGE TRUE
J 0
(-8450 2950);
DISPLAY 0.872340 (-8450 2950);
PAINT GREEN (-8450 2950);
DISPLAY INVISIBLE (-8450 2950);
FORCEPROP 1 LAST COMMENT_BODY TRUE
J 0
(-8650 2975);
DISPLAY 0.872340 (-8650 2975);
PAINT GREEN (-8650 2975);
DISPLAY INVISIBLE (-8650 2975);
FORCEPROP 2 LAST PATH I4
J 0
(-9025 3125);
DISPLAY 1.021277 (-9025 3125);
DISPLAY INVISIBLE (-9025 3125);
FORCEADD TAP..1
R 2
(-7800 5025);
FORCEPROP 3 LASTPIN (-7750 5025) SIG_NAME M_D_CPU1_SB_CA<3>
J 0
(-7740 5035);
DISPLAY 0.659574 (-7740 5035);
PAINT MONO (-7740 5035);
DISPLAY INVISIBLE (-7740 5035);
FORCEPROP 1 LASTPIN (-7750 5025) BN 3
J 2
(-7738 5033);
DISPLAY 0.489362 (-7738 5033);
PAINT GREEN (-7738 5033);
FORCEPROP 2 LAST CDS_LIB mstr_standard
J 0
(-7800 5025);
DISPLAY 0.723404 (-7800 5025);
PAINT MONO (-7800 5025);
DISPLAY INVISIBLE (-7800 5025);
FORCEPROP 1 LAST BODY_TYPE PLUMBING
J 2
(-7800 5075);
DISPLAY 0.872340 (-7800 5075);
PAINT GREEN (-7800 5075);
DISPLAY INVISIBLE (-7800 5075);
FORCEPROP 1 LAST HDL_TAP TRUE
J 2
(-8125 4900);
DISPLAY 0.872340 (-8125 4900);
DISPLAY INVISIBLE (-8125 4900);
FORCEPROP 1 LAST PATH I40
J 2
(-7798 5025);
DISPLAY 0.872340 (-7798 5025);
PAINT GREEN (-7798 5025);
DISPLAY INVISIBLE (-7798 5025);
FORCEADD TAP..1
R 2
(-7800 5075);
FORCEPROP 3 LASTPIN (-7750 5075) SIG_NAME M_D_CPU1_SB_CA<4>
J 0
(-7740 5085);
DISPLAY 0.659574 (-7740 5085);
PAINT MONO (-7740 5085);
DISPLAY INVISIBLE (-7740 5085);
FORCEPROP 1 LASTPIN (-7750 5075) BN 4
J 2
(-7738 5083);
DISPLAY 0.489362 (-7738 5083);
PAINT GREEN (-7738 5083);
FORCEPROP 2 LAST CDS_LIB mstr_standard
J 0
(-7800 5075);
DISPLAY 0.723404 (-7800 5075);
PAINT MONO (-7800 5075);
DISPLAY INVISIBLE (-7800 5075);
FORCEPROP 1 LAST BODY_TYPE PLUMBING
J 2
(-7800 5125);
DISPLAY 0.872340 (-7800 5125);
PAINT GREEN (-7800 5125);
DISPLAY INVISIBLE (-7800 5125);
FORCEPROP 1 LAST HDL_TAP TRUE
J 2
(-8125 4950);
DISPLAY 0.872340 (-8125 4950);
DISPLAY INVISIBLE (-8125 4950);
FORCEPROP 1 LAST PATH I41
J 2
(-7798 5075);
DISPLAY 0.872340 (-7798 5075);
PAINT GREEN (-7798 5075);
DISPLAY INVISIBLE (-7798 5075);
FORCEADD TAP..1
R 2
(-7800 5175);
FORCEPROP 3 LASTPIN (-7750 5175) SIG_NAME M_D_CPU1_SB_CA<6>
J 0
(-7740 5185);
DISPLAY 0.659574 (-7740 5185);
PAINT MONO (-7740 5185);
DISPLAY INVISIBLE (-7740 5185);
FORCEPROP 1 LASTPIN (-7750 5175) BN 6
J 2
(-7738 5183);
DISPLAY 0.489362 (-7738 5183);
PAINT GREEN (-7738 5183);
FORCEPROP 2 LAST CDS_LIB mstr_standard
J 0
(-7800 5175);
DISPLAY 0.723404 (-7800 5175);
PAINT MONO (-7800 5175);
DISPLAY INVISIBLE (-7800 5175);
FORCEPROP 1 LAST BODY_TYPE PLUMBING
J 2
(-7800 5225);
DISPLAY 0.872340 (-7800 5225);
PAINT GREEN (-7800 5225);
DISPLAY INVISIBLE (-7800 5225);
FORCEPROP 1 LAST HDL_TAP TRUE
J 2
(-8125 5050);
DISPLAY 0.872340 (-8125 5050);
DISPLAY INVISIBLE (-8125 5050);
FORCEPROP 1 LAST PATH I42
J 2
(-7798 5175);
DISPLAY 0.872340 (-7798 5175);
PAINT GREEN (-7798 5175);
DISPLAY INVISIBLE (-7798 5175);
FORCEADD TAP..1
R 2
(-7800 5125);
FORCEPROP 3 LASTPIN (-7750 5125) SIG_NAME M_D_CPU1_SB_CA<5>
J 0
(-7740 5135);
DISPLAY 0.659574 (-7740 5135);
PAINT MONO (-7740 5135);
DISPLAY INVISIBLE (-7740 5135);
FORCEPROP 1 LASTPIN (-7750 5125) BN 5
J 2
(-7738 5133);
DISPLAY 0.489362 (-7738 5133);
PAINT GREEN (-7738 5133);
FORCEPROP 2 LAST CDS_LIB mstr_standard
J 0
(-7800 5125);
DISPLAY 0.723404 (-7800 5125);
PAINT MONO (-7800 5125);
DISPLAY INVISIBLE (-7800 5125);
FORCEPROP 1 LAST BODY_TYPE PLUMBING
J 2
(-7800 5175);
DISPLAY 0.872340 (-7800 5175);
PAINT GREEN (-7800 5175);
DISPLAY INVISIBLE (-7800 5175);
FORCEPROP 1 LAST HDL_TAP TRUE
J 2
(-8125 5000);
DISPLAY 0.872340 (-8125 5000);
DISPLAY INVISIBLE (-8125 5000);
FORCEPROP 1 LAST PATH I43
J 2
(-7798 5125);
DISPLAY 0.872340 (-7798 5125);
PAINT GREEN (-7798 5125);
DISPLAY INVISIBLE (-7798 5125);
FORCEADD OFFPAGE..1
(-8400 5625);
FORCEPROP 2 LAST $XR0 40 
J 0
(-8621 5625);
DISPLAY 0.638298 (-8621 5625);
PAINT MONO (-8621 5625);
FORCEPROP 2 LAST CDS_LIB mstr_standard
J 0
(-8400 5625);
DISPLAY 0.723404 (-8400 5625);
PAINT MONO (-8400 5625);
DISPLAY INVISIBLE (-8400 5625);
FORCEPROP 1 LAST OFFPAGE TRUE
J 0
(-8075 5500);
DISPLAY 0.872340 (-8075 5500);
PAINT GREEN (-8075 5500);
DISPLAY INVISIBLE (-8075 5500);
FORCEPROP 1 LAST COMMENT_BODY TRUE
J 0
(-8275 5525);
DISPLAY 0.872340 (-8275 5525);
PAINT GREEN (-8275 5525);
DISPLAY INVISIBLE (-8275 5525);
FORCEPROP 2 LAST PATH I44
J 0
(-8650 5675);
DISPLAY 1.021277 (-8650 5675);
DISPLAY INVISIBLE (-8650 5675);
FORCEADD TAP..1
R 2
(-7800 5375);
FORCEPROP 3 LASTPIN (-7750 5375) SIG_NAME M_D_CPU1_SA_CA<2>
J 0
(-7740 5385);
DISPLAY 0.659574 (-7740 5385);
PAINT MONO (-7740 5385);
DISPLAY INVISIBLE (-7740 5385);
FORCEPROP 1 LASTPIN (-7750 5375) BN 2
J 2
(-7738 5383);
DISPLAY 0.489362 (-7738 5383);
PAINT GREEN (-7738 5383);
FORCEPROP 2 LAST CDS_LIB mstr_standard
J 0
(-7800 5375);
DISPLAY 0.723404 (-7800 5375);
PAINT MONO (-7800 5375);
DISPLAY INVISIBLE (-7800 5375);
FORCEPROP 1 LAST BODY_TYPE PLUMBING
J 2
(-7800 5425);
DISPLAY 0.872340 (-7800 5425);
PAINT GREEN (-7800 5425);
DISPLAY INVISIBLE (-7800 5425);
FORCEPROP 1 LAST HDL_TAP TRUE
J 2
(-8125 5250);
DISPLAY 0.872340 (-8125 5250);
DISPLAY INVISIBLE (-8125 5250);
FORCEPROP 1 LAST PATH I45
J 2
(-7798 5375);
DISPLAY 0.872340 (-7798 5375);
PAINT GREEN (-7798 5375);
DISPLAY INVISIBLE (-7798 5375);
FORCEADD TAP..1
R 2
(-7800 5425);
FORCEPROP 3 LASTPIN (-7750 5425) SIG_NAME M_D_CPU1_SA_CA<3>
J 0
(-7740 5435);
DISPLAY 0.659574 (-7740 5435);
PAINT MONO (-7740 5435);
DISPLAY INVISIBLE (-7740 5435);
FORCEPROP 1 LASTPIN (-7750 5425) BN 3
J 2
(-7738 5433);
DISPLAY 0.489362 (-7738 5433);
PAINT GREEN (-7738 5433);
FORCEPROP 2 LAST CDS_LIB mstr_standard
J 0
(-7800 5425);
DISPLAY 0.723404 (-7800 5425);
PAINT MONO (-7800 5425);
DISPLAY INVISIBLE (-7800 5425);
FORCEPROP 1 LAST BODY_TYPE PLUMBING
J 2
(-7800 5475);
DISPLAY 0.872340 (-7800 5475);
PAINT GREEN (-7800 5475);
DISPLAY INVISIBLE (-7800 5475);
FORCEPROP 1 LAST HDL_TAP TRUE
J 2
(-8125 5300);
DISPLAY 0.872340 (-8125 5300);
DISPLAY INVISIBLE (-8125 5300);
FORCEPROP 1 LAST PATH I46
J 2
(-7798 5425);
DISPLAY 0.872340 (-7798 5425);
PAINT GREEN (-7798 5425);
DISPLAY INVISIBLE (-7798 5425);
FORCEADD TAP..1
R 2
(-7800 5325);
FORCEPROP 3 LASTPIN (-7750 5325) SIG_NAME M_D_CPU1_SA_CA<1>
J 0
(-7740 5335);
DISPLAY 0.659574 (-7740 5335);
PAINT MONO (-7740 5335);
DISPLAY INVISIBLE (-7740 5335);
FORCEPROP 1 LASTPIN (-7750 5325) BN 1
J 2
(-7738 5333);
DISPLAY 0.489362 (-7738 5333);
PAINT GREEN (-7738 5333);
FORCEPROP 2 LAST CDS_LIB mstr_standard
J 0
(-7800 5325);
DISPLAY 0.723404 (-7800 5325);
PAINT MONO (-7800 5325);
DISPLAY INVISIBLE (-7800 5325);
FORCEPROP 1 LAST BODY_TYPE PLUMBING
J 2
(-7800 5375);
DISPLAY 0.872340 (-7800 5375);
PAINT GREEN (-7800 5375);
DISPLAY INVISIBLE (-7800 5375);
FORCEPROP 1 LAST HDL_TAP TRUE
J 2
(-8125 5200);
DISPLAY 0.872340 (-8125 5200);
DISPLAY INVISIBLE (-8125 5200);
FORCEPROP 1 LAST PATH I47
J 2
(-7798 5325);
DISPLAY 0.872340 (-7798 5325);
PAINT GREEN (-7798 5325);
DISPLAY INVISIBLE (-7798 5325);
FORCEADD TAP..1
R 2
(-7800 5275);
FORCEPROP 3 LASTPIN (-7750 5275) SIG_NAME M_D_CPU1_SA_CA<0>
J 0
(-7740 5285);
DISPLAY 0.659574 (-7740 5285);
PAINT MONO (-7740 5285);
DISPLAY INVISIBLE (-7740 5285);
FORCEPROP 1 LASTPIN (-7750 5275) BN 0
J 2
(-7738 5283);
DISPLAY 0.489362 (-7738 5283);
PAINT GREEN (-7738 5283);
FORCEPROP 2 LAST CDS_LIB mstr_standard
J 0
(-7800 5275);
DISPLAY 0.723404 (-7800 5275);
PAINT MONO (-7800 5275);
DISPLAY INVISIBLE (-7800 5275);
FORCEPROP 1 LAST BODY_TYPE PLUMBING
J 2
(-7800 5325);
DISPLAY 0.872340 (-7800 5325);
PAINT GREEN (-7800 5325);
DISPLAY INVISIBLE (-7800 5325);
FORCEPROP 1 LAST HDL_TAP TRUE
J 2
(-8125 5150);
DISPLAY 0.872340 (-8125 5150);
DISPLAY INVISIBLE (-8125 5150);
FORCEPROP 1 LAST PATH I48
J 2
(-7798 5275);
DISPLAY 0.872340 (-7798 5275);
PAINT GREEN (-7798 5275);
DISPLAY INVISIBLE (-7798 5275);
FORCEADD TAP..1
R 2
(-7800 5475);
FORCEPROP 3 LASTPIN (-7750 5475) SIG_NAME M_D_CPU1_SA_CA<4>
J 0
(-7740 5485);
DISPLAY 0.659574 (-7740 5485);
PAINT MONO (-7740 5485);
DISPLAY INVISIBLE (-7740 5485);
FORCEPROP 1 LASTPIN (-7750 5475) BN 4
J 2
(-7738 5483);
DISPLAY 0.489362 (-7738 5483);
PAINT GREEN (-7738 5483);
FORCEPROP 2 LAST CDS_LIB mstr_standard
J 0
(-7800 5475);
DISPLAY 0.723404 (-7800 5475);
PAINT MONO (-7800 5475);
DISPLAY INVISIBLE (-7800 5475);
FORCEPROP 1 LAST BODY_TYPE PLUMBING
J 2
(-7800 5525);
DISPLAY 0.872340 (-7800 5525);
PAINT GREEN (-7800 5525);
DISPLAY INVISIBLE (-7800 5525);
FORCEPROP 1 LAST HDL_TAP TRUE
J 2
(-8125 5350);
DISPLAY 0.872340 (-8125 5350);
DISPLAY INVISIBLE (-8125 5350);
FORCEPROP 1 LAST PATH I49
J 2
(-7798 5475);
DISPLAY 0.872340 (-7798 5475);
PAINT GREEN (-7798 5475);
DISPLAY INVISIBLE (-7798 5475);
FORCEADD TAP..1
R 2
(-7800 5575);
FORCEPROP 3 LASTPIN (-7750 5575) SIG_NAME M_D_CPU1_SA_CA<6>
J 0
(-7740 5585);
DISPLAY 0.659574 (-7740 5585);
PAINT MONO (-7740 5585);
DISPLAY INVISIBLE (-7740 5585);
FORCEPROP 1 LASTPIN (-7750 5575) BN 6
J 2
(-7738 5583);
DISPLAY 0.489362 (-7738 5583);
PAINT GREEN (-7738 5583);
FORCEPROP 2 LAST CDS_LIB mstr_standard
J 0
(-7800 5575);
DISPLAY 0.723404 (-7800 5575);
PAINT MONO (-7800 5575);
DISPLAY INVISIBLE (-7800 5575);
FORCEPROP 1 LAST BODY_TYPE PLUMBING
J 2
(-7800 5625);
DISPLAY 0.872340 (-7800 5625);
PAINT GREEN (-7800 5625);
DISPLAY INVISIBLE (-7800 5625);
FORCEPROP 1 LAST HDL_TAP TRUE
J 2
(-8125 5450);
DISPLAY 0.872340 (-8125 5450);
DISPLAY INVISIBLE (-8125 5450);
FORCEPROP 1 LAST PATH I50
J 2
(-7798 5575);
DISPLAY 0.872340 (-7798 5575);
PAINT GREEN (-7798 5575);
DISPLAY INVISIBLE (-7798 5575);
FORCEADD TAP..1
R 2
(-7800 5525);
FORCEPROP 3 LASTPIN (-7750 5525) SIG_NAME M_D_CPU1_SA_CA<5>
J 0
(-7740 5535);
DISPLAY 0.659574 (-7740 5535);
PAINT MONO (-7740 5535);
DISPLAY INVISIBLE (-7740 5535);
FORCEPROP 1 LASTPIN (-7750 5525) BN 5
J 2
(-7738 5533);
DISPLAY 0.489362 (-7738 5533);
PAINT GREEN (-7738 5533);
FORCEPROP 2 LAST CDS_LIB mstr_standard
J 0
(-7800 5525);
DISPLAY 0.723404 (-7800 5525);
PAINT MONO (-7800 5525);
DISPLAY INVISIBLE (-7800 5525);
FORCEPROP 1 LAST BODY_TYPE PLUMBING
J 2
(-7800 5575);
DISPLAY 0.872340 (-7800 5575);
PAINT GREEN (-7800 5575);
DISPLAY INVISIBLE (-7800 5575);
FORCEPROP 1 LAST HDL_TAP TRUE
J 2
(-8125 5400);
DISPLAY 0.872340 (-8125 5400);
DISPLAY INVISIBLE (-8125 5400);
FORCEPROP 1 LAST PATH I51
J 2
(-7798 5525);
DISPLAY 0.872340 (-7798 5525);
PAINT GREEN (-7798 5525);
DISPLAY INVISIBLE (-7798 5525);
FORCEADD SCONN288_DDR506112002KQ..1
(-6950 3825);
FORCEPROP 1 LAST LOCATION J30
J 0
(-7400 5900);
DISPLAY 0.468085 (-7400 5900);
PAINT SKYBLUE (-7400 5900);
FORCEPROP 0 LAST $SEC 1
J 0
(-7400 6050);
DISPLAY 0.680851 (-7400 6050);
PAINT MONO (-7400 6050);
DISPLAY INVISIBLE (-7400 6050);
FORCEPROP 2 LAST CDS_SEC 1
J 0
(-7400 6050);
DISPLAY 1.021277 (-7400 6050);
DISPLAY INVISIBLE (-7400 6050);
FORCEPROP 0 LASTPIN (-7550 3225) $PN 62
J 2
(-7560 3235);
DISPLAY 0.680851 (-7560 3235);
PAINT MONO (-7560 3235);
FORCEPROP 0 LASTPIN (-7550 5275) $PN 66
J 2
(-7560 5285);
DISPLAY 0.680851 (-7560 5285);
PAINT MONO (-7560 5285);
FORCEPROP 0 LASTPIN (-7550 4875) $PN 76
J 2
(-7560 4885);
DISPLAY 0.680851 (-7560 4885);
PAINT MONO (-7560 4885);
FORCEPROP 0 LASTPIN (-7550 5325) $PN 211
J 2
(-7560 5335);
DISPLAY 0.680851 (-7560 5335);
PAINT MONO (-7560 5335);
FORCEPROP 0 LASTPIN (-7550 4925) $PN 221
J 2
(-7560 4935);
DISPLAY 0.680851 (-7560 4935);
PAINT MONO (-7560 4935);
FORCEPROP 0 LASTPIN (-7550 5375) $PN 68
J 2
(-7560 5385);
DISPLAY 0.680851 (-7560 5385);
PAINT MONO (-7560 5385);
FORCEPROP 0 LASTPIN (-7550 4975) $PN 78
J 2
(-7560 4985);
DISPLAY 0.680851 (-7560 4985);
PAINT MONO (-7560 4985);
FORCEPROP 0 LASTPIN (-7550 5425) $PN 213
J 2
(-7560 5435);
DISPLAY 0.680851 (-7560 5435);
PAINT MONO (-7560 5435);
FORCEPROP 0 LASTPIN (-7550 5025) $PN 223
J 2
(-7560 5035);
DISPLAY 0.680851 (-7560 5035);
PAINT MONO (-7560 5035);
FORCEPROP 0 LASTPIN (-7550 5475) $PN 70
J 2
(-7560 5485);
DISPLAY 0.680851 (-7560 5485);
PAINT MONO (-7560 5485);
FORCEPROP 0 LASTPIN (-7550 5075) $PN 80
J 2
(-7560 5085);
DISPLAY 0.680851 (-7560 5085);
PAINT MONO (-7560 5085);
FORCEPROP 0 LASTPIN (-7550 5525) $PN 215
J 2
(-7560 5535);
DISPLAY 0.680851 (-7560 5535);
PAINT MONO (-7560 5535);
FORCEPROP 0 LASTPIN (-7550 5125) $PN 225
J 2
(-7560 5135);
DISPLAY 0.680851 (-7560 5135);
PAINT MONO (-7560 5135);
FORCEPROP 0 LASTPIN (-7550 5575) $PN 72
J 2
(-7560 5585);
DISPLAY 0.680851 (-7560 5585);
PAINT MONO (-7560 5585);
FORCEPROP 0 LASTPIN (-7550 5175) $PN 82
J 2
(-7560 5185);
DISPLAY 0.680851 (-7560 5185);
PAINT MONO (-7560 5185);
FORCEPROP 0 LASTPIN (-7550 3825) $PN 51
J 2
(-7560 3835);
DISPLAY 0.680851 (-7560 3835);
PAINT MONO (-7560 3835);
FORCEPROP 0 LASTPIN (-7550 3375) $PN 96
J 2
(-7560 3385);
DISPLAY 0.680851 (-7560 3385);
PAINT MONO (-7560 3385);
FORCEPROP 0 LASTPIN (-7550 3875) $PN 53
J 2
(-7560 3885);
DISPLAY 0.680851 (-7560 3885);
PAINT MONO (-7560 3885);
FORCEPROP 0 LASTPIN (-7550 3425) $PN 98
J 2
(-7560 3435);
DISPLAY 0.680851 (-7560 3435);
PAINT MONO (-7560 3435);
FORCEPROP 0 LASTPIN (-7550 3925) $PN 196
J 2
(-7560 3935);
DISPLAY 0.680851 (-7560 3935);
PAINT MONO (-7560 3935);
FORCEPROP 0 LASTPIN (-7550 3475) $PN 241
J 2
(-7560 3485);
DISPLAY 0.680851 (-7560 3485);
PAINT MONO (-7560 3485);
FORCEPROP 0 LASTPIN (-7550 3975) $PN 198
J 2
(-7560 3985);
DISPLAY 0.680851 (-7560 3985);
PAINT MONO (-7560 3985);
FORCEPROP 0 LASTPIN (-7550 3525) $PN 243
J 2
(-7560 3535);
DISPLAY 0.680851 (-7560 3535);
PAINT MONO (-7560 3535);
FORCEPROP 0 LASTPIN (-7550 4025) $PN 58
J 2
(-7560 4035);
DISPLAY 0.680851 (-7560 4035);
PAINT MONO (-7560 4035);
FORCEPROP 0 LASTPIN (-7550 3575) $PN 89
J 2
(-7560 3585);
DISPLAY 0.680851 (-7560 3585);
PAINT MONO (-7560 3585);
FORCEPROP 0 LASTPIN (-7550 4075) $PN 60
J 2
(-7560 4085);
DISPLAY 0.680851 (-7560 4085);
PAINT MONO (-7560 4085);
FORCEPROP 0 LASTPIN (-7550 3625) $PN 91
J 2
(-7560 3635);
DISPLAY 0.680851 (-7560 3635);
PAINT MONO (-7560 3635);
FORCEPROP 0 LASTPIN (-7550 4125) $PN 203
J 2
(-7560 4135);
DISPLAY 0.680851 (-7560 4135);
PAINT MONO (-7560 4135);
FORCEPROP 0 LASTPIN (-7550 3675) $PN 234
J 2
(-7560 3685);
DISPLAY 0.680851 (-7560 3685);
PAINT MONO (-7560 3685);
FORCEPROP 0 LASTPIN (-7550 4175) $PN 205
J 2
(-7560 4185);
DISPLAY 0.680851 (-7560 4185);
PAINT MONO (-7560 4185);
FORCEPROP 0 LASTPIN (-7550 3725) $PN 236
J 2
(-7560 3735);
DISPLAY 0.680851 (-7560 3735);
PAINT MONO (-7560 3735);
FORCEPROP 0 LASTPIN (-7550 4275) $PN 218
J 2
(-7560 4285);
DISPLAY 0.680851 (-7560 4285);
PAINT MONO (-7560 4285);
FORCEPROP 0 LASTPIN (-7550 4325) $PN 217
J 2
(-7560 4335);
DISPLAY 0.680851 (-7560 4335);
PAINT MONO (-7560 4335);
FORCEPROP 0 LASTPIN (-7550 4575) $PN 64
J 2
(-7560 4585);
DISPLAY 0.680851 (-7560 4585);
PAINT MONO (-7560 4585);
FORCEPROP 0 LASTPIN (-7550 4425) $PN 84
J 2
(-7560 4435);
DISPLAY 0.680851 (-7560 4435);
PAINT MONO (-7560 4435);
FORCEPROP 0 LASTPIN (-7550 4625) $PN 209
J 2
(-7560 4635);
DISPLAY 0.680851 (-7560 4635);
PAINT MONO (-7560 4635);
FORCEPROP 0 LASTPIN (-7550 4475) $PN 229
J 2
(-7560 4485);
DISPLAY 0.680851 (-7560 4485);
PAINT MONO (-7560 4485);
FORCEPROP 0 LASTPIN (-6350 4025) $PN 7
J 0
(-6340 4035);
DISPLAY 0.680851 (-6340 4035);
PAINT MONO (-6340 4035);
FORCEPROP 0 LASTPIN (-6350 2375) $PN 100
J 0
(-6340 2385);
DISPLAY 0.680851 (-6340 2385);
PAINT MONO (-6340 2385);
FORCEPROP 0 LASTPIN (-6350 4075) $PN 9
J 0
(-6340 4085);
DISPLAY 0.680851 (-6340 4085);
PAINT MONO (-6340 4085);
FORCEPROP 0 LASTPIN (-6350 2425) $PN 102
J 0
(-6340 2435);
DISPLAY 0.680851 (-6340 2435);
PAINT MONO (-6340 2435);
FORCEPROP 0 LASTPIN (-6350 4125) $PN 152
J 0
(-6340 4135);
DISPLAY 0.680851 (-6340 4135);
PAINT MONO (-6340 4135);
FORCEPROP 0 LASTPIN (-6350 2475) $PN 245
J 0
(-6340 2485);
DISPLAY 0.680851 (-6340 2485);
PAINT MONO (-6340 2485);
FORCEPROP 0 LASTPIN (-6350 4175) $PN 154
J 0
(-6340 4185);
DISPLAY 0.680851 (-6340 4185);
PAINT MONO (-6340 4185);
FORCEPROP 0 LASTPIN (-6350 2525) $PN 247
J 0
(-6340 2535);
DISPLAY 0.680851 (-6340 2535);
PAINT MONO (-6340 2535);
FORCEPROP 0 LASTPIN (-6350 4225) $PN 14
J 0
(-6340 4235);
DISPLAY 0.680851 (-6340 4235);
PAINT MONO (-6340 4235);
FORCEPROP 0 LASTPIN (-6350 2575) $PN 107
J 0
(-6340 2585);
DISPLAY 0.680851 (-6340 2585);
PAINT MONO (-6340 2585);
FORCEPROP 0 LASTPIN (-6350 4275) $PN 16
J 0
(-6340 4285);
DISPLAY 0.680851 (-6340 4285);
PAINT MONO (-6340 4285);
FORCEPROP 0 LASTPIN (-6350 2625) $PN 109
J 0
(-6340 2635);
DISPLAY 0.680851 (-6340 2635);
PAINT MONO (-6340 2635);
FORCEPROP 0 LASTPIN (-6350 4325) $PN 159
J 0
(-6340 4335);
DISPLAY 0.680851 (-6340 4335);
PAINT MONO (-6340 4335);
FORCEPROP 0 LASTPIN (-6350 2675) $PN 252
J 0
(-6340 2685);
DISPLAY 0.680851 (-6340 2685);
PAINT MONO (-6340 2685);
FORCEPROP 0 LASTPIN (-6350 4375) $PN 161
J 0
(-6340 4385);
DISPLAY 0.680851 (-6340 4385);
PAINT MONO (-6340 4385);
FORCEPROP 0 LASTPIN (-6350 2725) $PN 254
J 0
(-6340 2735);
DISPLAY 0.680851 (-6340 2735);
PAINT MONO (-6340 2735);
FORCEPROP 0 LASTPIN (-6350 4425) $PN 18
J 0
(-6340 4435);
DISPLAY 0.680851 (-6340 4435);
PAINT MONO (-6340 4435);
FORCEPROP 0 LASTPIN (-6350 2775) $PN 111
J 0
(-6340 2785);
DISPLAY 0.680851 (-6340 2785);
PAINT MONO (-6340 2785);
FORCEPROP 0 LASTPIN (-6350 4475) $PN 20
J 0
(-6340 4485);
DISPLAY 0.680851 (-6340 4485);
PAINT MONO (-6340 4485);
FORCEPROP 0 LASTPIN (-6350 2825) $PN 113
J 0
(-6340 2835);
DISPLAY 0.680851 (-6340 2835);
PAINT MONO (-6340 2835);
FORCEPROP 0 LASTPIN (-6350 4525) $PN 163
J 0
(-6340 4535);
DISPLAY 0.680851 (-6340 4535);
PAINT MONO (-6340 4535);
FORCEPROP 0 LASTPIN (-6350 2875) $PN 256
J 0
(-6340 2885);
DISPLAY 0.680851 (-6340 2885);
PAINT MONO (-6340 2885);
FORCEPROP 0 LASTPIN (-6350 4575) $PN 165
J 0
(-6340 4585);
DISPLAY 0.680851 (-6340 4585);
PAINT MONO (-6340 4585);
FORCEPROP 0 LASTPIN (-6350 2925) $PN 258
J 0
(-6340 2935);
DISPLAY 0.680851 (-6340 2935);
PAINT MONO (-6340 2935);
FORCEPROP 0 LASTPIN (-6350 4625) $PN 25
J 0
(-6340 4635);
DISPLAY 0.680851 (-6340 4635);
PAINT MONO (-6340 4635);
FORCEPROP 0 LASTPIN (-6350 2975) $PN 118
J 0
(-6340 2985);
DISPLAY 0.680851 (-6340 2985);
PAINT MONO (-6340 2985);
FORCEPROP 0 LASTPIN (-6350 4675) $PN 27
J 0
(-6340 4685);
DISPLAY 0.680851 (-6340 4685);
PAINT MONO (-6340 4685);
FORCEPROP 0 LASTPIN (-6350 3025) $PN 120
J 0
(-6340 3035);
DISPLAY 0.680851 (-6340 3035);
PAINT MONO (-6340 3035);
FORCEPROP 0 LASTPIN (-6350 4725) $PN 170
J 0
(-6340 4735);
DISPLAY 0.680851 (-6340 4735);
PAINT MONO (-6340 4735);
FORCEPROP 0 LASTPIN (-6350 3075) $PN 263
J 0
(-6340 3085);
DISPLAY 0.680851 (-6340 3085);
PAINT MONO (-6340 3085);
FORCEPROP 0 LASTPIN (-6350 4775) $PN 172
J 0
(-6340 4785);
DISPLAY 0.680851 (-6340 4785);
PAINT MONO (-6340 4785);
FORCEPROP 0 LASTPIN (-6350 3125) $PN 265
J 0
(-6340 3135);
DISPLAY 0.680851 (-6340 3135);
PAINT MONO (-6340 3135);
FORCEPROP 0 LASTPIN (-6350 4825) $PN 29
J 0
(-6340 4835);
DISPLAY 0.680851 (-6340 4835);
PAINT MONO (-6340 4835);
FORCEPROP 0 LASTPIN (-6350 3175) $PN 122
J 0
(-6340 3185);
DISPLAY 0.680851 (-6340 3185);
PAINT MONO (-6340 3185);
FORCEPROP 0 LASTPIN (-6350 4875) $PN 31
J 0
(-6340 4885);
DISPLAY 0.680851 (-6340 4885);
PAINT MONO (-6340 4885);
FORCEPROP 0 LASTPIN (-6350 3225) $PN 124
J 0
(-6340 3235);
DISPLAY 0.680851 (-6340 3235);
PAINT MONO (-6340 3235);
FORCEPROP 0 LASTPIN (-6350 4925) $PN 174
J 0
(-6340 4935);
DISPLAY 0.680851 (-6340 4935);
PAINT MONO (-6340 4935);
FORCEPROP 0 LASTPIN (-6350 3275) $PN 267
J 0
(-6340 3285);
DISPLAY 0.680851 (-6340 3285);
PAINT MONO (-6340 3285);
FORCEPROP 0 LASTPIN (-6350 4975) $PN 176
J 0
(-6340 4985);
DISPLAY 0.680851 (-6340 4985);
PAINT MONO (-6340 4985);
FORCEPROP 0 LASTPIN (-6350 3325) $PN 269
J 0
(-6340 3335);
DISPLAY 0.680851 (-6340 3335);
PAINT MONO (-6340 3335);
FORCEPROP 0 LASTPIN (-6350 5025) $PN 36
J 0
(-6340 5035);
DISPLAY 0.680851 (-6340 5035);
PAINT MONO (-6340 5035);
FORCEPROP 0 LASTPIN (-6350 3375) $PN 129
J 0
(-6340 3385);
DISPLAY 0.680851 (-6340 3385);
PAINT MONO (-6340 3385);
FORCEPROP 0 LASTPIN (-6350 5075) $PN 38
J 0
(-6340 5085);
DISPLAY 0.680851 (-6340 5085);
PAINT MONO (-6340 5085);
FORCEPROP 0 LASTPIN (-6350 3425) $PN 131
J 0
(-6340 3435);
DISPLAY 0.680851 (-6340 3435);
PAINT MONO (-6340 3435);
FORCEPROP 0 LASTPIN (-6350 5125) $PN 181
J 0
(-6340 5135);
DISPLAY 0.680851 (-6340 5135);
PAINT MONO (-6340 5135);
FORCEPROP 0 LASTPIN (-6350 3475) $PN 274
J 0
(-6340 3485);
DISPLAY 0.680851 (-6340 3485);
PAINT MONO (-6340 3485);
FORCEPROP 0 LASTPIN (-6350 5175) $PN 183
J 0
(-6340 5185);
DISPLAY 0.680851 (-6340 5185);
PAINT MONO (-6340 5185);
FORCEPROP 0 LASTPIN (-6350 3525) $PN 276
J 0
(-6340 3535);
DISPLAY 0.680851 (-6340 3535);
PAINT MONO (-6340 3535);
FORCEPROP 0 LASTPIN (-6350 5225) $PN 40
J 0
(-6340 5235);
DISPLAY 0.680851 (-6340 5235);
PAINT MONO (-6340 5235);
FORCEPROP 0 LASTPIN (-6350 3575) $PN 133
J 0
(-6340 3585);
DISPLAY 0.680851 (-6340 3585);
PAINT MONO (-6340 3585);
FORCEPROP 0 LASTPIN (-6350 5275) $PN 42
J 0
(-6340 5285);
DISPLAY 0.680851 (-6340 5285);
PAINT MONO (-6340 5285);
FORCEPROP 0 LASTPIN (-6350 3625) $PN 135
J 0
(-6340 3635);
DISPLAY 0.680851 (-6340 3635);
PAINT MONO (-6340 3635);
FORCEPROP 0 LASTPIN (-6350 5325) $PN 185
J 0
(-6340 5335);
DISPLAY 0.680851 (-6340 5335);
PAINT MONO (-6340 5335);
FORCEPROP 0 LASTPIN (-6350 3675) $PN 278
J 0
(-6340 3685);
DISPLAY 0.680851 (-6340 3685);
PAINT MONO (-6340 3685);
FORCEPROP 0 LASTPIN (-6350 5375) $PN 187
J 0
(-6340 5385);
DISPLAY 0.680851 (-6340 5385);
PAINT MONO (-6340 5385);
FORCEPROP 0 LASTPIN (-6350 3725) $PN 280
J 0
(-6340 3735);
DISPLAY 0.680851 (-6340 3735);
PAINT MONO (-6340 3735);
FORCEPROP 0 LASTPIN (-6350 5425) $PN 47
J 0
(-6340 5435);
DISPLAY 0.680851 (-6340 5435);
PAINT MONO (-6340 5435);
FORCEPROP 0 LASTPIN (-6350 3775) $PN 140
J 0
(-6340 3785);
DISPLAY 0.680851 (-6340 3785);
PAINT MONO (-6340 3785);
FORCEPROP 0 LASTPIN (-6350 5475) $PN 49
J 0
(-6340 5485);
DISPLAY 0.680851 (-6340 5485);
PAINT MONO (-6340 5485);
FORCEPROP 0 LASTPIN (-6350 3825) $PN 142
J 0
(-6340 3835);
DISPLAY 0.680851 (-6340 3835);
PAINT MONO (-6340 3835);
FORCEPROP 0 LASTPIN (-6350 5525) $PN 192
J 0
(-6340 5535);
DISPLAY 0.680851 (-6340 5535);
PAINT MONO (-6340 5535);
FORCEPROP 0 LASTPIN (-6350 3875) $PN 285
J 0
(-6340 3885);
DISPLAY 0.680851 (-6340 3885);
PAINT MONO (-6340 3885);
FORCEPROP 0 LASTPIN (-6350 5575) $PN 194
J 0
(-6340 5585);
DISPLAY 0.680851 (-6340 5585);
PAINT MONO (-6340 5585);
FORCEPROP 0 LASTPIN (-6350 3925) $PN 287
J 0
(-6340 3935);
DISPLAY 0.680851 (-6340 3935);
PAINT MONO (-6340 3935);
FORCEPROP 0 LASTPIN (-7550 3075) $PN 148
J 2
(-7560 3085);
DISPLAY 0.680851 (-7560 3085);
PAINT MONO (-7560 3085);
FORCEPROP 0 LASTPIN (-7550 2975) $PN 4
J 2
(-7560 2985);
DISPLAY 0.680851 (-7560 2985);
PAINT MONO (-7560 2985);
FORCEPROP 0 LASTPIN (-7550 3025) $PN 5
J 2
(-7560 3035);
DISPLAY 0.680851 (-7560 3035);
PAINT MONO (-7560 3035);
FORCEPROP 0 LASTPIN (-7550 2175) $PN 86
J 2
(-7560 2185);
DISPLAY 0.680851 (-7560 2185);
PAINT MONO (-7560 2185);
FORCEPROP 0 LASTPIN (-7550 2125) $PN 87
J 2
(-7560 2135);
DISPLAY 0.680851 (-7560 2135);
PAINT MONO (-7560 2135);
FORCEPROP 0 LASTPIN (-7550 4775) $PN 74
J 2
(-7560 4785);
DISPLAY 0.680851 (-7560 4785);
PAINT MONO (-7560 4785);
FORCEPROP 0 LASTPIN (-7550 4725) $PN 227
J 2
(-7560 4735);
DISPLAY 0.680851 (-7560 4735);
PAINT MONO (-7560 4735);
FORCEPROP 0 LASTPIN (-7550 2725) $PN 147
J 2
(-7560 2735);
DISPLAY 0.680851 (-7560 2735);
PAINT MONO (-7560 2735);
FORCEPROP 0 LASTPIN (-7550 3275) $PN 207
J 2
(-7560 3285);
DISPLAY 0.680851 (-7560 3285);
PAINT MONO (-7560 3285);
FORCEPROP 0 LASTPIN (-7550 2325) $PN 2
J 2
(-7560 2335);
DISPLAY 0.680851 (-7560 2335);
PAINT MONO (-7560 2335);
FORCEPROP 0 LASTPIN (-7550 2375) $PN 144
J 2
(-7560 2385);
DISPLAY 0.680851 (-7560 2385);
PAINT MONO (-7560 2385);
FORCEPROP 0 LASTPIN (-7550 2425) $PN 149
J 2
(-7560 2435);
DISPLAY 0.680851 (-7560 2435);
PAINT MONO (-7560 2435);
FORCEPROP 0 LASTPIN (-7550 2475) $PN 150
J 2
(-7560 2485);
DISPLAY 0.680851 (-7560 2485);
PAINT MONO (-7560 2485);
FORCEPROP 0 LASTPIN (-7550 2525) $PN 220
J 2
(-7560 2535);
DISPLAY 0.680851 (-7560 2535);
PAINT MONO (-7560 2535);
FORCEPROP 0 LASTPIN (-7550 2575) $PN 231
J 2
(-7560 2585);
DISPLAY 0.680851 (-7560 2585);
PAINT MONO (-7560 2585);
FORCEPROP 0 LASTPIN (-7550 2625) $PN 232
J 2
(-7560 2635);
DISPLAY 0.680851 (-7560 2635);
PAINT MONO (-7560 2635);
FORCEPROP 0 LASTPIN (-7550 3125) $PN 3
J 2
(-7560 3135);
DISPLAY 0.680851 (-7560 3135);
PAINT MONO (-7560 3135);
FORCEPROP 2 LAST VALUE SCONN288_DDR506112002KQ
J 0
(-7400 5950);
DISPLAY 0.489362 (-7400 5950);
PAINT SKYBLUE (-7400 5950);
FORCEPROP 1 LAST MATERIAL IO
J 0
(-7400 5750);
DISPLAY 0.468085 (-7400 5750);
PAINT SKYBLUE (-7400 5750);
FORCEPROP 2 LAST PART_TYPE SMLF
J 0
(-7400 6000);
DISPLAY 1.021277 (-7400 6000);
FORCEPROP 2 LAST CDS_LIB pure_quanta
J 0
(-6950 3825);
DISPLAY INVISIBLE (-6950 3825);
FORCEPROP 1 LAST NEEDS_NO_SIZE TRUE
J 0
(-6950 3825);
DISPLAY 0.723404 (-6950 3825);
PAINT GREEN (-6950 3825);
DISPLAY INVISIBLE (-6950 3825);
FORCEPROP 1 LAST CDS_LMAN_SYM_OUTLINE -450,1900,450,-1850
J 0
(-6950 3825);
DISPLAY 0.468085 (-6950 3825);
PAINT GREEN (-6950 3825);
DISPLAY INVISIBLE (-6950 3825);
FORCEPROP 1 LAST PATH I52
J 0
(-6950 3825);
DISPLAY 0.723404 (-6950 3825);
PAINT GREEN (-6950 3825);
DISPLAY INVISIBLE (-6950 3825);
FORCEPROP 1 LAST PART_NUMBER DFHST8FS479
J 0
(-7400 5825);
DISPLAY 0.468085 (-7400 5825);
PAINT SKYBLUE (-7400 5825);
DISPLAY INVISIBLE (-7400 5825);
FORCEADD TAP..1
(-6100 2375);
FORCEPROP 3 LASTPIN (-6150 2375) SIG_NAME M_D_CPU1_SB_DQ<0>
J 0
(-6140 2385);
DISPLAY 0.659574 (-6140 2385);
PAINT MONO (-6140 2385);
DISPLAY INVISIBLE (-6140 2385);
FORCEPROP 1 LASTPIN (-6150 2375) BN 0
J 0
(-6162 2383);
DISPLAY 0.489362 (-6162 2383);
PAINT GREEN (-6162 2383);
FORCEPROP 2 LAST CDS_LIB mstr_standard
J 0
(-6100 2375);
DISPLAY 0.723404 (-6100 2375);
PAINT MONO (-6100 2375);
DISPLAY INVISIBLE (-6100 2375);
FORCEPROP 1 LAST BODY_TYPE PLUMBING
J 0
(-6100 2425);
DISPLAY 0.872340 (-6100 2425);
PAINT GREEN (-6100 2425);
DISPLAY INVISIBLE (-6100 2425);
FORCEPROP 1 LAST HDL_TAP TRUE
J 0
(-5775 2250);
DISPLAY 0.872340 (-5775 2250);
DISPLAY INVISIBLE (-5775 2250);
FORCEPROP 1 LAST PATH I53
J 0
(-6102 2375);
DISPLAY 0.872340 (-6102 2375);
PAINT GREEN (-6102 2375);
DISPLAY INVISIBLE (-6102 2375);
FORCEADD TAP..1
(-6100 2425);
FORCEPROP 3 LASTPIN (-6150 2425) SIG_NAME M_D_CPU1_SB_DQ<1>
J 0
(-6140 2435);
DISPLAY 0.659574 (-6140 2435);
PAINT MONO (-6140 2435);
DISPLAY INVISIBLE (-6140 2435);
FORCEPROP 1 LASTPIN (-6150 2425) BN 1
J 0
(-6162 2433);
DISPLAY 0.489362 (-6162 2433);
PAINT GREEN (-6162 2433);
FORCEPROP 2 LAST CDS_LIB mstr_standard
J 0
(-6100 2425);
DISPLAY 0.723404 (-6100 2425);
PAINT MONO (-6100 2425);
DISPLAY INVISIBLE (-6100 2425);
FORCEPROP 1 LAST BODY_TYPE PLUMBING
J 0
(-6100 2475);
DISPLAY 0.872340 (-6100 2475);
PAINT GREEN (-6100 2475);
DISPLAY INVISIBLE (-6100 2475);
FORCEPROP 1 LAST HDL_TAP TRUE
J 0
(-5775 2300);
DISPLAY 0.872340 (-5775 2300);
DISPLAY INVISIBLE (-5775 2300);
FORCEPROP 1 LAST PATH I54
J 0
(-6102 2425);
DISPLAY 0.872340 (-6102 2425);
PAINT GREEN (-6102 2425);
DISPLAY INVISIBLE (-6102 2425);
FORCEADD TAP..1
(-6100 2525);
FORCEPROP 3 LASTPIN (-6150 2525) SIG_NAME M_D_CPU1_SB_DQ<3>
J 0
(-6140 2535);
DISPLAY 0.659574 (-6140 2535);
PAINT MONO (-6140 2535);
DISPLAY INVISIBLE (-6140 2535);
FORCEPROP 1 LASTPIN (-6150 2525) BN 3
J 0
(-6162 2533);
DISPLAY 0.489362 (-6162 2533);
PAINT GREEN (-6162 2533);
FORCEPROP 2 LAST CDS_LIB mstr_standard
J 0
(-6100 2525);
DISPLAY 0.723404 (-6100 2525);
PAINT MONO (-6100 2525);
DISPLAY INVISIBLE (-6100 2525);
FORCEPROP 1 LAST BODY_TYPE PLUMBING
J 0
(-6100 2575);
DISPLAY 0.872340 (-6100 2575);
PAINT GREEN (-6100 2575);
DISPLAY INVISIBLE (-6100 2575);
FORCEPROP 1 LAST HDL_TAP TRUE
J 0
(-5775 2400);
DISPLAY 0.872340 (-5775 2400);
DISPLAY INVISIBLE (-5775 2400);
FORCEPROP 1 LAST PATH I55
J 0
(-6102 2525);
DISPLAY 0.872340 (-6102 2525);
PAINT GREEN (-6102 2525);
DISPLAY INVISIBLE (-6102 2525);
FORCEADD TAP..1
(-6100 2475);
FORCEPROP 3 LASTPIN (-6150 2475) SIG_NAME M_D_CPU1_SB_DQ<2>
J 0
(-6140 2485);
DISPLAY 0.659574 (-6140 2485);
PAINT MONO (-6140 2485);
DISPLAY INVISIBLE (-6140 2485);
FORCEPROP 1 LASTPIN (-6150 2475) BN 2
J 0
(-6162 2483);
DISPLAY 0.489362 (-6162 2483);
PAINT GREEN (-6162 2483);
FORCEPROP 2 LAST CDS_LIB mstr_standard
J 0
(-6100 2475);
DISPLAY 0.723404 (-6100 2475);
PAINT MONO (-6100 2475);
DISPLAY INVISIBLE (-6100 2475);
FORCEPROP 1 LAST BODY_TYPE PLUMBING
J 0
(-6100 2525);
DISPLAY 0.872340 (-6100 2525);
PAINT GREEN (-6100 2525);
DISPLAY INVISIBLE (-6100 2525);
FORCEPROP 1 LAST HDL_TAP TRUE
J 0
(-5775 2350);
DISPLAY 0.872340 (-5775 2350);
DISPLAY INVISIBLE (-5775 2350);
FORCEPROP 1 LAST PATH I56
J 0
(-6102 2475);
DISPLAY 0.872340 (-6102 2475);
PAINT GREEN (-6102 2475);
DISPLAY INVISIBLE (-6102 2475);
FORCEADD TAP..1
(-6100 2575);
FORCEPROP 3 LASTPIN (-6150 2575) SIG_NAME M_D_CPU1_SB_DQ<4>
J 0
(-6140 2585);
DISPLAY 0.659574 (-6140 2585);
PAINT MONO (-6140 2585);
DISPLAY INVISIBLE (-6140 2585);
FORCEPROP 1 LASTPIN (-6150 2575) BN 4
J 0
(-6162 2583);
DISPLAY 0.489362 (-6162 2583);
PAINT GREEN (-6162 2583);
FORCEPROP 2 LAST CDS_LIB mstr_standard
J 0
(-6100 2575);
DISPLAY 0.723404 (-6100 2575);
PAINT MONO (-6100 2575);
DISPLAY INVISIBLE (-6100 2575);
FORCEPROP 1 LAST BODY_TYPE PLUMBING
J 0
(-6100 2625);
DISPLAY 0.872340 (-6100 2625);
PAINT GREEN (-6100 2625);
DISPLAY INVISIBLE (-6100 2625);
FORCEPROP 1 LAST HDL_TAP TRUE
J 0
(-5775 2450);
DISPLAY 0.872340 (-5775 2450);
DISPLAY INVISIBLE (-5775 2450);
FORCEPROP 1 LAST PATH I57
J 0
(-6102 2575);
DISPLAY 0.872340 (-6102 2575);
PAINT GREEN (-6102 2575);
DISPLAY INVISIBLE (-6102 2575);
FORCEADD TAP..1
(-6100 2625);
FORCEPROP 3 LASTPIN (-6150 2625) SIG_NAME M_D_CPU1_SB_DQ<5>
J 0
(-6140 2635);
DISPLAY 0.659574 (-6140 2635);
PAINT MONO (-6140 2635);
DISPLAY INVISIBLE (-6140 2635);
FORCEPROP 1 LASTPIN (-6150 2625) BN 5
J 0
(-6162 2633);
DISPLAY 0.489362 (-6162 2633);
PAINT GREEN (-6162 2633);
FORCEPROP 2 LAST CDS_LIB mstr_standard
J 0
(-6100 2625);
DISPLAY 0.723404 (-6100 2625);
PAINT MONO (-6100 2625);
DISPLAY INVISIBLE (-6100 2625);
FORCEPROP 1 LAST BODY_TYPE PLUMBING
J 0
(-6100 2675);
DISPLAY 0.872340 (-6100 2675);
PAINT GREEN (-6100 2675);
DISPLAY INVISIBLE (-6100 2675);
FORCEPROP 1 LAST HDL_TAP TRUE
J 0
(-5775 2500);
DISPLAY 0.872340 (-5775 2500);
DISPLAY INVISIBLE (-5775 2500);
FORCEPROP 1 LAST PATH I58
J 0
(-6102 2625);
DISPLAY 0.872340 (-6102 2625);
PAINT GREEN (-6102 2625);
DISPLAY INVISIBLE (-6102 2625);
FORCEADD TAP..1
(-6100 2675);
FORCEPROP 3 LASTPIN (-6150 2675) SIG_NAME M_D_CPU1_SB_DQ<6>
J 0
(-6140 2685);
DISPLAY 0.659574 (-6140 2685);
PAINT MONO (-6140 2685);
DISPLAY INVISIBLE (-6140 2685);
FORCEPROP 1 LASTPIN (-6150 2675) BN 6
J 0
(-6162 2683);
DISPLAY 0.489362 (-6162 2683);
PAINT GREEN (-6162 2683);
FORCEPROP 2 LAST CDS_LIB mstr_standard
J 0
(-6100 2675);
DISPLAY 0.723404 (-6100 2675);
PAINT MONO (-6100 2675);
DISPLAY INVISIBLE (-6100 2675);
FORCEPROP 1 LAST BODY_TYPE PLUMBING
J 0
(-6100 2725);
DISPLAY 0.872340 (-6100 2725);
PAINT GREEN (-6100 2725);
DISPLAY INVISIBLE (-6100 2725);
FORCEPROP 1 LAST HDL_TAP TRUE
J 0
(-5775 2550);
DISPLAY 0.872340 (-5775 2550);
DISPLAY INVISIBLE (-5775 2550);
FORCEPROP 1 LAST PATH I59
J 0
(-6102 2675);
DISPLAY 0.872340 (-6102 2675);
PAINT GREEN (-6102 2675);
DISPLAY INVISIBLE (-6102 2675);
FORCEADD TAP..1
(-6100 2775);
FORCEPROP 3 LASTPIN (-6150 2775) SIG_NAME M_D_CPU1_SB_DQ<8>
J 0
(-6140 2785);
DISPLAY 0.659574 (-6140 2785);
PAINT MONO (-6140 2785);
DISPLAY INVISIBLE (-6140 2785);
FORCEPROP 1 LASTPIN (-6150 2775) BN 8
J 0
(-6162 2783);
DISPLAY 0.489362 (-6162 2783);
PAINT GREEN (-6162 2783);
FORCEPROP 2 LAST CDS_LIB mstr_standard
J 0
(-6100 2775);
DISPLAY 0.723404 (-6100 2775);
PAINT MONO (-6100 2775);
DISPLAY INVISIBLE (-6100 2775);
FORCEPROP 1 LAST BODY_TYPE PLUMBING
J 0
(-6100 2825);
DISPLAY 0.872340 (-6100 2825);
PAINT GREEN (-6100 2825);
DISPLAY INVISIBLE (-6100 2825);
FORCEPROP 1 LAST HDL_TAP TRUE
J 0
(-5775 2650);
DISPLAY 0.872340 (-5775 2650);
DISPLAY INVISIBLE (-5775 2650);
FORCEPROP 1 LAST PATH I60
J 0
(-6102 2775);
DISPLAY 0.872340 (-6102 2775);
PAINT GREEN (-6102 2775);
DISPLAY INVISIBLE (-6102 2775);
FORCEADD TAP..1
(-6100 2725);
FORCEPROP 3 LASTPIN (-6150 2725) SIG_NAME M_D_CPU1_SB_DQ<7>
J 0
(-6140 2735);
DISPLAY 0.659574 (-6140 2735);
PAINT MONO (-6140 2735);
DISPLAY INVISIBLE (-6140 2735);
FORCEPROP 1 LASTPIN (-6150 2725) BN 7
J 0
(-6162 2733);
DISPLAY 0.489362 (-6162 2733);
PAINT GREEN (-6162 2733);
FORCEPROP 2 LAST CDS_LIB mstr_standard
J 0
(-6100 2725);
DISPLAY 0.723404 (-6100 2725);
PAINT MONO (-6100 2725);
DISPLAY INVISIBLE (-6100 2725);
FORCEPROP 1 LAST BODY_TYPE PLUMBING
J 0
(-6100 2775);
DISPLAY 0.872340 (-6100 2775);
PAINT GREEN (-6100 2775);
DISPLAY INVISIBLE (-6100 2775);
FORCEPROP 1 LAST HDL_TAP TRUE
J 0
(-5775 2600);
DISPLAY 0.872340 (-5775 2600);
DISPLAY INVISIBLE (-5775 2600);
FORCEPROP 1 LAST PATH I61
J 0
(-6102 2725);
DISPLAY 0.872340 (-6102 2725);
PAINT GREEN (-6102 2725);
DISPLAY INVISIBLE (-6102 2725);
FORCEADD TAP..1
(-6100 2825);
FORCEPROP 3 LASTPIN (-6150 2825) SIG_NAME M_D_CPU1_SB_DQ<9>
J 0
(-6140 2835);
DISPLAY 0.659574 (-6140 2835);
PAINT MONO (-6140 2835);
DISPLAY INVISIBLE (-6140 2835);
FORCEPROP 1 LASTPIN (-6150 2825) BN 9
J 0
(-6162 2833);
DISPLAY 0.489362 (-6162 2833);
PAINT GREEN (-6162 2833);
FORCEPROP 2 LAST CDS_LIB mstr_standard
J 0
(-6100 2825);
DISPLAY 0.723404 (-6100 2825);
PAINT MONO (-6100 2825);
DISPLAY INVISIBLE (-6100 2825);
FORCEPROP 1 LAST BODY_TYPE PLUMBING
J 0
(-6100 2875);
DISPLAY 0.872340 (-6100 2875);
PAINT GREEN (-6100 2875);
DISPLAY INVISIBLE (-6100 2875);
FORCEPROP 1 LAST HDL_TAP TRUE
J 0
(-5775 2700);
DISPLAY 0.872340 (-5775 2700);
DISPLAY INVISIBLE (-5775 2700);
FORCEPROP 1 LAST PATH I62
J 0
(-6102 2825);
DISPLAY 0.872340 (-6102 2825);
PAINT GREEN (-6102 2825);
DISPLAY INVISIBLE (-6102 2825);
FORCEADD TAP..1
(-6100 2875);
FORCEPROP 3 LASTPIN (-6150 2875) SIG_NAME M_D_CPU1_SB_DQ<10>
J 0
(-6140 2885);
DISPLAY 0.659574 (-6140 2885);
PAINT MONO (-6140 2885);
DISPLAY INVISIBLE (-6140 2885);
FORCEPROP 1 LASTPIN (-6150 2875) BN 10
J 0
(-6162 2883);
DISPLAY 0.489362 (-6162 2883);
PAINT GREEN (-6162 2883);
FORCEPROP 2 LAST CDS_LIB mstr_standard
J 0
(-6100 2875);
DISPLAY 0.723404 (-6100 2875);
PAINT MONO (-6100 2875);
DISPLAY INVISIBLE (-6100 2875);
FORCEPROP 1 LAST BODY_TYPE PLUMBING
J 0
(-6100 2925);
DISPLAY 0.872340 (-6100 2925);
PAINT GREEN (-6100 2925);
DISPLAY INVISIBLE (-6100 2925);
FORCEPROP 1 LAST HDL_TAP TRUE
J 0
(-5775 2750);
DISPLAY 0.872340 (-5775 2750);
DISPLAY INVISIBLE (-5775 2750);
FORCEPROP 1 LAST PATH I63
J 0
(-6102 2875);
DISPLAY 0.872340 (-6102 2875);
PAINT GREEN (-6102 2875);
DISPLAY INVISIBLE (-6102 2875);
FORCEADD TAP..1
(-6100 2925);
FORCEPROP 3 LASTPIN (-6150 2925) SIG_NAME M_D_CPU1_SB_DQ<11>
J 0
(-6140 2935);
DISPLAY 0.659574 (-6140 2935);
PAINT MONO (-6140 2935);
DISPLAY INVISIBLE (-6140 2935);
FORCEPROP 1 LASTPIN (-6150 2925) BN 11
J 0
(-6162 2933);
DISPLAY 0.489362 (-6162 2933);
PAINT GREEN (-6162 2933);
FORCEPROP 2 LAST CDS_LIB mstr_standard
J 0
(-6100 2925);
DISPLAY 0.723404 (-6100 2925);
PAINT MONO (-6100 2925);
DISPLAY INVISIBLE (-6100 2925);
FORCEPROP 1 LAST BODY_TYPE PLUMBING
J 0
(-6100 2975);
DISPLAY 0.872340 (-6100 2975);
PAINT GREEN (-6100 2975);
DISPLAY INVISIBLE (-6100 2975);
FORCEPROP 1 LAST HDL_TAP TRUE
J 0
(-5775 2800);
DISPLAY 0.872340 (-5775 2800);
DISPLAY INVISIBLE (-5775 2800);
FORCEPROP 1 LAST PATH I64
J 0
(-6102 2925);
DISPLAY 0.872340 (-6102 2925);
PAINT GREEN (-6102 2925);
DISPLAY INVISIBLE (-6102 2925);
FORCEADD TAP..1
(-6100 2975);
FORCEPROP 3 LASTPIN (-6150 2975) SIG_NAME M_D_CPU1_SB_DQ<12>
J 0
(-6140 2985);
DISPLAY 0.659574 (-6140 2985);
PAINT MONO (-6140 2985);
DISPLAY INVISIBLE (-6140 2985);
FORCEPROP 1 LASTPIN (-6150 2975) BN 12
J 0
(-6162 2983);
DISPLAY 0.489362 (-6162 2983);
PAINT GREEN (-6162 2983);
FORCEPROP 2 LAST CDS_LIB mstr_standard
J 0
(-6100 2975);
DISPLAY 0.723404 (-6100 2975);
PAINT MONO (-6100 2975);
DISPLAY INVISIBLE (-6100 2975);
FORCEPROP 1 LAST BODY_TYPE PLUMBING
J 0
(-6100 3025);
DISPLAY 0.872340 (-6100 3025);
PAINT GREEN (-6100 3025);
DISPLAY INVISIBLE (-6100 3025);
FORCEPROP 1 LAST HDL_TAP TRUE
J 0
(-5775 2850);
DISPLAY 0.872340 (-5775 2850);
DISPLAY INVISIBLE (-5775 2850);
FORCEPROP 1 LAST PATH I65
J 0
(-6102 2975);
DISPLAY 0.872340 (-6102 2975);
PAINT GREEN (-6102 2975);
DISPLAY INVISIBLE (-6102 2975);
FORCEADD TAP..1
(-6100 3025);
FORCEPROP 3 LASTPIN (-6150 3025) SIG_NAME M_D_CPU1_SB_DQ<13>
J 0
(-6140 3035);
DISPLAY 0.659574 (-6140 3035);
PAINT MONO (-6140 3035);
DISPLAY INVISIBLE (-6140 3035);
FORCEPROP 1 LASTPIN (-6150 3025) BN 13
J 0
(-6162 3033);
DISPLAY 0.489362 (-6162 3033);
PAINT GREEN (-6162 3033);
FORCEPROP 2 LAST CDS_LIB mstr_standard
J 0
(-6100 3025);
DISPLAY 0.723404 (-6100 3025);
PAINT MONO (-6100 3025);
DISPLAY INVISIBLE (-6100 3025);
FORCEPROP 1 LAST BODY_TYPE PLUMBING
J 0
(-6100 3075);
DISPLAY 0.872340 (-6100 3075);
PAINT GREEN (-6100 3075);
DISPLAY INVISIBLE (-6100 3075);
FORCEPROP 1 LAST HDL_TAP TRUE
J 0
(-5775 2900);
DISPLAY 0.872340 (-5775 2900);
DISPLAY INVISIBLE (-5775 2900);
FORCEPROP 1 LAST PATH I66
J 0
(-6102 3025);
DISPLAY 0.872340 (-6102 3025);
PAINT GREEN (-6102 3025);
DISPLAY INVISIBLE (-6102 3025);
FORCEADD TAP..1
(-6100 3125);
FORCEPROP 3 LASTPIN (-6150 3125) SIG_NAME M_D_CPU1_SB_DQ<15>
J 0
(-6140 3135);
DISPLAY 0.659574 (-6140 3135);
PAINT MONO (-6140 3135);
DISPLAY INVISIBLE (-6140 3135);
FORCEPROP 1 LASTPIN (-6150 3125) BN 15
J 0
(-6162 3133);
DISPLAY 0.489362 (-6162 3133);
PAINT GREEN (-6162 3133);
FORCEPROP 2 LAST CDS_LIB mstr_standard
J 0
(-6100 3125);
DISPLAY 0.723404 (-6100 3125);
PAINT MONO (-6100 3125);
DISPLAY INVISIBLE (-6100 3125);
FORCEPROP 1 LAST BODY_TYPE PLUMBING
J 0
(-6100 3175);
DISPLAY 0.872340 (-6100 3175);
PAINT GREEN (-6100 3175);
DISPLAY INVISIBLE (-6100 3175);
FORCEPROP 1 LAST HDL_TAP TRUE
J 0
(-5775 3000);
DISPLAY 0.872340 (-5775 3000);
DISPLAY INVISIBLE (-5775 3000);
FORCEPROP 1 LAST PATH I67
J 0
(-6102 3125);
DISPLAY 0.872340 (-6102 3125);
PAINT GREEN (-6102 3125);
DISPLAY INVISIBLE (-6102 3125);
FORCEADD TAP..1
(-6100 3075);
FORCEPROP 3 LASTPIN (-6150 3075) SIG_NAME M_D_CPU1_SB_DQ<14>
J 0
(-6140 3085);
DISPLAY 0.659574 (-6140 3085);
PAINT MONO (-6140 3085);
DISPLAY INVISIBLE (-6140 3085);
FORCEPROP 1 LASTPIN (-6150 3075) BN 14
J 0
(-6162 3083);
DISPLAY 0.489362 (-6162 3083);
PAINT GREEN (-6162 3083);
FORCEPROP 2 LAST CDS_LIB mstr_standard
J 0
(-6100 3075);
DISPLAY 0.723404 (-6100 3075);
PAINT MONO (-6100 3075);
DISPLAY INVISIBLE (-6100 3075);
FORCEPROP 1 LAST BODY_TYPE PLUMBING
J 0
(-6100 3125);
DISPLAY 0.872340 (-6100 3125);
PAINT GREEN (-6100 3125);
DISPLAY INVISIBLE (-6100 3125);
FORCEPROP 1 LAST HDL_TAP TRUE
J 0
(-5775 2950);
DISPLAY 0.872340 (-5775 2950);
DISPLAY INVISIBLE (-5775 2950);
FORCEPROP 1 LAST PATH I68
J 0
(-6102 3075);
DISPLAY 0.872340 (-6102 3075);
PAINT GREEN (-6102 3075);
DISPLAY INVISIBLE (-6102 3075);
FORCEADD TAP..1
(-6100 3175);
FORCEPROP 3 LASTPIN (-6150 3175) SIG_NAME M_D_CPU1_SB_DQ<16>
J 0
(-6140 3185);
DISPLAY 0.659574 (-6140 3185);
PAINT MONO (-6140 3185);
DISPLAY INVISIBLE (-6140 3185);
FORCEPROP 1 LASTPIN (-6150 3175) BN 16
J 0
(-6162 3183);
DISPLAY 0.489362 (-6162 3183);
PAINT GREEN (-6162 3183);
FORCEPROP 2 LAST CDS_LIB mstr_standard
J 0
(-6100 3175);
DISPLAY 0.723404 (-6100 3175);
PAINT MONO (-6100 3175);
DISPLAY INVISIBLE (-6100 3175);
FORCEPROP 1 LAST BODY_TYPE PLUMBING
J 0
(-6100 3225);
DISPLAY 0.872340 (-6100 3225);
PAINT GREEN (-6100 3225);
DISPLAY INVISIBLE (-6100 3225);
FORCEPROP 1 LAST HDL_TAP TRUE
J 0
(-5775 3050);
DISPLAY 0.872340 (-5775 3050);
DISPLAY INVISIBLE (-5775 3050);
FORCEPROP 1 LAST PATH I69
J 0
(-6102 3175);
DISPLAY 0.872340 (-6102 3175);
PAINT GREEN (-6102 3175);
DISPLAY INVISIBLE (-6102 3175);
FORCEADD VCC_CORE..1
(-8650 3600);
FORCEPROP 3 LASTPIN (-8650 3550) SIG_NAME P3V3_AUX\g
J 0
(-8640 3560);
DISPLAY 0.659574 (-8640 3560);
PAINT MONO (-8640 3560);
DISPLAY INVISIBLE (-8640 3560);
FORCEPROP 1 LAST HDL_POWER P3V3_AUX
J 1
(-8650 3650);
DISPLAY 0.489362 (-8650 3650);
PAINT GREEN (-8650 3650);
FORCEPROP 2 LAST ROOM PVCCINFAON_CPU1_CTRL
J 0
(-8650 3700);
DISPLAY 0.808511 (-8650 3700);
PAINT RED (-8650 3700);
DISPLAY INVISIBLE (-8650 3700);
FORCEPROP 0 LAST VOLTAGE 3.3
J 0
(-8925 3750);
DISPLAY 1.021277 (-8925 3750);
PAINT SKYBLUE (-8925 3750);
DISPLAY INVISIBLE (-8925 3750);
FORCEPROP 2 LAST CDS_LIB mstr_symbols
J 0
(-8650 3600);
PAINT MONO (-8650 3600);
DISPLAY INVISIBLE (-8650 3600);
FORCEPROP 1 LAST PATH I7
J 0
(-8600 3625);
DISPLAY 0.872340 (-8600 3625);
PAINT AQUA (-8600 3625);
DISPLAY INVISIBLE (-8600 3625);
FORCEADD TAP..1
(-6100 3225);
FORCEPROP 3 LASTPIN (-6150 3225) SIG_NAME M_D_CPU1_SB_DQ<17>
J 0
(-6140 3235);
DISPLAY 0.659574 (-6140 3235);
PAINT MONO (-6140 3235);
DISPLAY INVISIBLE (-6140 3235);
FORCEPROP 1 LASTPIN (-6150 3225) BN 17
J 0
(-6162 3233);
DISPLAY 0.489362 (-6162 3233);
PAINT GREEN (-6162 3233);
FORCEPROP 2 LAST CDS_LIB mstr_standard
J 0
(-6100 3225);
DISPLAY 0.723404 (-6100 3225);
PAINT MONO (-6100 3225);
DISPLAY INVISIBLE (-6100 3225);
FORCEPROP 1 LAST BODY_TYPE PLUMBING
J 0
(-6100 3275);
DISPLAY 0.872340 (-6100 3275);
PAINT GREEN (-6100 3275);
DISPLAY INVISIBLE (-6100 3275);
FORCEPROP 1 LAST HDL_TAP TRUE
J 0
(-5775 3100);
DISPLAY 0.872340 (-5775 3100);
DISPLAY INVISIBLE (-5775 3100);
FORCEPROP 1 LAST PATH I70
J 0
(-6102 3225);
DISPLAY 0.872340 (-6102 3225);
PAINT GREEN (-6102 3225);
DISPLAY INVISIBLE (-6102 3225);
FORCEADD TAP..1
(-6100 3275);
FORCEPROP 3 LASTPIN (-6150 3275) SIG_NAME M_D_CPU1_SB_DQ<18>
J 0
(-6140 3285);
DISPLAY 0.659574 (-6140 3285);
PAINT MONO (-6140 3285);
DISPLAY INVISIBLE (-6140 3285);
FORCEPROP 1 LASTPIN (-6150 3275) BN 18
J 0
(-6162 3283);
DISPLAY 0.489362 (-6162 3283);
PAINT GREEN (-6162 3283);
FORCEPROP 2 LAST CDS_LIB mstr_standard
J 0
(-6100 3275);
DISPLAY 0.723404 (-6100 3275);
PAINT MONO (-6100 3275);
DISPLAY INVISIBLE (-6100 3275);
FORCEPROP 1 LAST BODY_TYPE PLUMBING
J 0
(-6100 3325);
DISPLAY 0.872340 (-6100 3325);
PAINT GREEN (-6100 3325);
DISPLAY INVISIBLE (-6100 3325);
FORCEPROP 1 LAST HDL_TAP TRUE
J 0
(-5775 3150);
DISPLAY 0.872340 (-5775 3150);
DISPLAY INVISIBLE (-5775 3150);
FORCEPROP 1 LAST PATH I71
J 0
(-6102 3275);
DISPLAY 0.872340 (-6102 3275);
PAINT GREEN (-6102 3275);
DISPLAY INVISIBLE (-6102 3275);
FORCEADD TAP..1
(-6100 3325);
FORCEPROP 3 LASTPIN (-6150 3325) SIG_NAME M_D_CPU1_SB_DQ<19>
J 0
(-6140 3335);
DISPLAY 0.659574 (-6140 3335);
PAINT MONO (-6140 3335);
DISPLAY INVISIBLE (-6140 3335);
FORCEPROP 1 LASTPIN (-6150 3325) BN 19
J 0
(-6162 3333);
DISPLAY 0.489362 (-6162 3333);
PAINT GREEN (-6162 3333);
FORCEPROP 2 LAST CDS_LIB mstr_standard
J 0
(-6100 3325);
DISPLAY 0.723404 (-6100 3325);
PAINT MONO (-6100 3325);
DISPLAY INVISIBLE (-6100 3325);
FORCEPROP 1 LAST BODY_TYPE PLUMBING
J 0
(-6100 3375);
DISPLAY 0.872340 (-6100 3375);
PAINT GREEN (-6100 3375);
DISPLAY INVISIBLE (-6100 3375);
FORCEPROP 1 LAST HDL_TAP TRUE
J 0
(-5775 3200);
DISPLAY 0.872340 (-5775 3200);
DISPLAY INVISIBLE (-5775 3200);
FORCEPROP 1 LAST PATH I72
J 0
(-6102 3325);
DISPLAY 0.872340 (-6102 3325);
PAINT GREEN (-6102 3325);
DISPLAY INVISIBLE (-6102 3325);
FORCEADD TAP..1
(-6100 3425);
FORCEPROP 3 LASTPIN (-6150 3425) SIG_NAME M_D_CPU1_SB_DQ<21>
J 0
(-6140 3435);
DISPLAY 0.659574 (-6140 3435);
PAINT MONO (-6140 3435);
DISPLAY INVISIBLE (-6140 3435);
FORCEPROP 1 LASTPIN (-6150 3425) BN 21
J 0
(-6162 3433);
DISPLAY 0.489362 (-6162 3433);
PAINT GREEN (-6162 3433);
FORCEPROP 2 LAST CDS_LIB mstr_standard
J 0
(-6100 3425);
DISPLAY 0.723404 (-6100 3425);
PAINT MONO (-6100 3425);
DISPLAY INVISIBLE (-6100 3425);
FORCEPROP 1 LAST BODY_TYPE PLUMBING
J 0
(-6100 3475);
DISPLAY 0.872340 (-6100 3475);
PAINT GREEN (-6100 3475);
DISPLAY INVISIBLE (-6100 3475);
FORCEPROP 1 LAST HDL_TAP TRUE
J 0
(-5775 3300);
DISPLAY 0.872340 (-5775 3300);
DISPLAY INVISIBLE (-5775 3300);
FORCEPROP 1 LAST PATH I73
J 0
(-6102 3425);
DISPLAY 0.872340 (-6102 3425);
PAINT GREEN (-6102 3425);
DISPLAY INVISIBLE (-6102 3425);
FORCEADD TAP..1
(-6100 3375);
FORCEPROP 3 LASTPIN (-6150 3375) SIG_NAME M_D_CPU1_SB_DQ<20>
J 0
(-6140 3385);
DISPLAY 0.659574 (-6140 3385);
PAINT MONO (-6140 3385);
DISPLAY INVISIBLE (-6140 3385);
FORCEPROP 1 LASTPIN (-6150 3375) BN 20
J 0
(-6162 3383);
DISPLAY 0.489362 (-6162 3383);
PAINT GREEN (-6162 3383);
FORCEPROP 2 LAST CDS_LIB mstr_standard
J 0
(-6100 3375);
DISPLAY 0.723404 (-6100 3375);
PAINT MONO (-6100 3375);
DISPLAY INVISIBLE (-6100 3375);
FORCEPROP 1 LAST BODY_TYPE PLUMBING
J 0
(-6100 3425);
DISPLAY 0.872340 (-6100 3425);
PAINT GREEN (-6100 3425);
DISPLAY INVISIBLE (-6100 3425);
FORCEPROP 1 LAST HDL_TAP TRUE
J 0
(-5775 3250);
DISPLAY 0.872340 (-5775 3250);
DISPLAY INVISIBLE (-5775 3250);
FORCEPROP 1 LAST PATH I74
J 0
(-6102 3375);
DISPLAY 0.872340 (-6102 3375);
PAINT GREEN (-6102 3375);
DISPLAY INVISIBLE (-6102 3375);
FORCEADD TAP..1
(-6100 3475);
FORCEPROP 3 LASTPIN (-6150 3475) SIG_NAME M_D_CPU1_SB_DQ<22>
J 0
(-6140 3485);
DISPLAY 0.659574 (-6140 3485);
PAINT MONO (-6140 3485);
DISPLAY INVISIBLE (-6140 3485);
FORCEPROP 1 LASTPIN (-6150 3475) BN 22
J 0
(-6162 3483);
DISPLAY 0.489362 (-6162 3483);
PAINT GREEN (-6162 3483);
FORCEPROP 2 LAST CDS_LIB mstr_standard
J 0
(-6100 3475);
DISPLAY 0.723404 (-6100 3475);
PAINT MONO (-6100 3475);
DISPLAY INVISIBLE (-6100 3475);
FORCEPROP 1 LAST BODY_TYPE PLUMBING
J 0
(-6100 3525);
DISPLAY 0.872340 (-6100 3525);
PAINT GREEN (-6100 3525);
DISPLAY INVISIBLE (-6100 3525);
FORCEPROP 1 LAST HDL_TAP TRUE
J 0
(-5775 3350);
DISPLAY 0.872340 (-5775 3350);
DISPLAY INVISIBLE (-5775 3350);
FORCEPROP 1 LAST PATH I75
J 0
(-6102 3475);
DISPLAY 0.872340 (-6102 3475);
PAINT GREEN (-6102 3475);
DISPLAY INVISIBLE (-6102 3475);
FORCEADD TAP..1
(-6100 3525);
FORCEPROP 3 LASTPIN (-6150 3525) SIG_NAME M_D_CPU1_SB_DQ<23>
J 0
(-6140 3535);
DISPLAY 0.659574 (-6140 3535);
PAINT MONO (-6140 3535);
DISPLAY INVISIBLE (-6140 3535);
FORCEPROP 1 LASTPIN (-6150 3525) BN 23
J 0
(-6162 3533);
DISPLAY 0.489362 (-6162 3533);
PAINT GREEN (-6162 3533);
FORCEPROP 2 LAST CDS_LIB mstr_standard
J 0
(-6100 3525);
DISPLAY 0.723404 (-6100 3525);
PAINT MONO (-6100 3525);
DISPLAY INVISIBLE (-6100 3525);
FORCEPROP 1 LAST BODY_TYPE PLUMBING
J 0
(-6100 3575);
DISPLAY 0.872340 (-6100 3575);
PAINT GREEN (-6100 3575);
DISPLAY INVISIBLE (-6100 3575);
FORCEPROP 1 LAST HDL_TAP TRUE
J 0
(-5775 3400);
DISPLAY 0.872340 (-5775 3400);
DISPLAY INVISIBLE (-5775 3400);
FORCEPROP 1 LAST PATH I76
J 0
(-6102 3525);
DISPLAY 0.872340 (-6102 3525);
PAINT GREEN (-6102 3525);
DISPLAY INVISIBLE (-6102 3525);
FORCEADD TAP..1
(-6100 3575);
FORCEPROP 3 LASTPIN (-6150 3575) SIG_NAME M_D_CPU1_SB_DQ<24>
J 0
(-6140 3585);
DISPLAY 0.659574 (-6140 3585);
PAINT MONO (-6140 3585);
DISPLAY INVISIBLE (-6140 3585);
FORCEPROP 1 LASTPIN (-6150 3575) BN 24
J 0
(-6162 3583);
DISPLAY 0.489362 (-6162 3583);
PAINT GREEN (-6162 3583);
FORCEPROP 2 LAST CDS_LIB mstr_standard
J 0
(-6100 3575);
DISPLAY 0.723404 (-6100 3575);
PAINT MONO (-6100 3575);
DISPLAY INVISIBLE (-6100 3575);
FORCEPROP 1 LAST BODY_TYPE PLUMBING
J 0
(-6100 3625);
DISPLAY 0.872340 (-6100 3625);
PAINT GREEN (-6100 3625);
DISPLAY INVISIBLE (-6100 3625);
FORCEPROP 1 LAST HDL_TAP TRUE
J 0
(-5775 3450);
DISPLAY 0.872340 (-5775 3450);
DISPLAY INVISIBLE (-5775 3450);
FORCEPROP 1 LAST PATH I77
J 0
(-6102 3575);
DISPLAY 0.872340 (-6102 3575);
PAINT GREEN (-6102 3575);
DISPLAY INVISIBLE (-6102 3575);
FORCEADD TAP..1
(-6100 3675);
FORCEPROP 3 LASTPIN (-6150 3675) SIG_NAME M_D_CPU1_SB_DQ<26>
J 0
(-6140 3685);
DISPLAY 0.659574 (-6140 3685);
PAINT MONO (-6140 3685);
DISPLAY INVISIBLE (-6140 3685);
FORCEPROP 1 LASTPIN (-6150 3675) BN 26
J 0
(-6162 3683);
DISPLAY 0.489362 (-6162 3683);
PAINT GREEN (-6162 3683);
FORCEPROP 2 LAST CDS_LIB mstr_standard
J 0
(-6100 3675);
DISPLAY 0.723404 (-6100 3675);
PAINT MONO (-6100 3675);
DISPLAY INVISIBLE (-6100 3675);
FORCEPROP 1 LAST BODY_TYPE PLUMBING
J 0
(-6100 3725);
DISPLAY 0.872340 (-6100 3725);
PAINT GREEN (-6100 3725);
DISPLAY INVISIBLE (-6100 3725);
FORCEPROP 1 LAST HDL_TAP TRUE
J 0
(-5775 3550);
DISPLAY 0.872340 (-5775 3550);
DISPLAY INVISIBLE (-5775 3550);
FORCEPROP 1 LAST PATH I78
J 0
(-6102 3675);
DISPLAY 0.872340 (-6102 3675);
PAINT GREEN (-6102 3675);
DISPLAY INVISIBLE (-6102 3675);
FORCEADD TAP..1
(-6100 3625);
FORCEPROP 3 LASTPIN (-6150 3625) SIG_NAME M_D_CPU1_SB_DQ<25>
J 0
(-6140 3635);
DISPLAY 0.659574 (-6140 3635);
PAINT MONO (-6140 3635);
DISPLAY INVISIBLE (-6140 3635);
FORCEPROP 1 LASTPIN (-6150 3625) BN 25
J 0
(-6162 3633);
DISPLAY 0.489362 (-6162 3633);
PAINT GREEN (-6162 3633);
FORCEPROP 2 LAST CDS_LIB mstr_standard
J 0
(-6100 3625);
DISPLAY 0.723404 (-6100 3625);
PAINT MONO (-6100 3625);
DISPLAY INVISIBLE (-6100 3625);
FORCEPROP 1 LAST BODY_TYPE PLUMBING
J 0
(-6100 3675);
DISPLAY 0.872340 (-6100 3675);
PAINT GREEN (-6100 3675);
DISPLAY INVISIBLE (-6100 3675);
FORCEPROP 1 LAST HDL_TAP TRUE
J 0
(-5775 3500);
DISPLAY 0.872340 (-5775 3500);
DISPLAY INVISIBLE (-5775 3500);
FORCEPROP 1 LAST PATH I79
J 0
(-6102 3625);
DISPLAY 0.872340 (-6102 3625);
PAINT GREEN (-6102 3625);
DISPLAY INVISIBLE (-6102 3625);
FORCEADD OFFPAGE..5
(-8250 3225);
FORCEPROP 2 LAST $XR0 40 
J 0
(-8474 3225);
DISPLAY 0.638298 (-8474 3225);
PAINT MONO (-8474 3225);
FORCEPROP 2 LAST CDS_LIB mstr_standard
J 0
(-8250 3225);
DISPLAY INVISIBLE (-8250 3225);
FORCEPROP 1 LAST OFFPAGE TRUE
J 0
(-7925 3100);
DISPLAY 0.872340 (-7925 3100);
PAINT GREEN (-7925 3100);
DISPLAY INVISIBLE (-7925 3100);
FORCEPROP 1 LAST COMMENT_BODY TRUE
J 0
(-8150 3150);
DISPLAY 0.872340 (-8150 3150);
PAINT GREEN (-8150 3150);
DISPLAY INVISIBLE (-8150 3150);
FORCEPROP 2 LAST PATH I8
J 0
(-8550 3275);
DISPLAY 1.021277 (-8550 3275);
DISPLAY INVISIBLE (-8550 3275);
FORCEADD TAP..1
(-6100 3725);
FORCEPROP 3 LASTPIN (-6150 3725) SIG_NAME M_D_CPU1_SB_DQ<27>
J 0
(-6140 3735);
DISPLAY 0.659574 (-6140 3735);
PAINT MONO (-6140 3735);
DISPLAY INVISIBLE (-6140 3735);
FORCEPROP 1 LASTPIN (-6150 3725) BN 27
J 0
(-6162 3733);
DISPLAY 0.489362 (-6162 3733);
PAINT GREEN (-6162 3733);
FORCEPROP 2 LAST CDS_LIB mstr_standard
J 0
(-6100 3725);
DISPLAY 0.723404 (-6100 3725);
PAINT MONO (-6100 3725);
DISPLAY INVISIBLE (-6100 3725);
FORCEPROP 1 LAST BODY_TYPE PLUMBING
J 0
(-6100 3775);
DISPLAY 0.872340 (-6100 3775);
PAINT GREEN (-6100 3775);
DISPLAY INVISIBLE (-6100 3775);
FORCEPROP 1 LAST HDL_TAP TRUE
J 0
(-5775 3600);
DISPLAY 0.872340 (-5775 3600);
DISPLAY INVISIBLE (-5775 3600);
FORCEPROP 1 LAST PATH I80
J 0
(-6102 3725);
DISPLAY 0.872340 (-6102 3725);
PAINT GREEN (-6102 3725);
DISPLAY INVISIBLE (-6102 3725);
FORCEADD TAP..1
(-6100 3775);
FORCEPROP 3 LASTPIN (-6150 3775) SIG_NAME M_D_CPU1_SB_DQ<28>
J 0
(-6140 3785);
DISPLAY 0.659574 (-6140 3785);
PAINT MONO (-6140 3785);
DISPLAY INVISIBLE (-6140 3785);
FORCEPROP 1 LASTPIN (-6150 3775) BN 28
J 0
(-6162 3783);
DISPLAY 0.489362 (-6162 3783);
PAINT GREEN (-6162 3783);
FORCEPROP 2 LAST CDS_LIB mstr_standard
J 0
(-6100 3775);
DISPLAY 0.723404 (-6100 3775);
PAINT MONO (-6100 3775);
DISPLAY INVISIBLE (-6100 3775);
FORCEPROP 1 LAST BODY_TYPE PLUMBING
J 0
(-6100 3825);
DISPLAY 0.872340 (-6100 3825);
PAINT GREEN (-6100 3825);
DISPLAY INVISIBLE (-6100 3825);
FORCEPROP 1 LAST HDL_TAP TRUE
J 0
(-5775 3650);
DISPLAY 0.872340 (-5775 3650);
DISPLAY INVISIBLE (-5775 3650);
FORCEPROP 1 LAST PATH I81
J 0
(-6102 3775);
DISPLAY 0.872340 (-6102 3775);
PAINT GREEN (-6102 3775);
DISPLAY INVISIBLE (-6102 3775);
FORCEADD TAP..1
(-6100 3875);
FORCEPROP 3 LASTPIN (-6150 3875) SIG_NAME M_D_CPU1_SB_DQ<30>
J 0
(-6140 3885);
DISPLAY 0.659574 (-6140 3885);
PAINT MONO (-6140 3885);
DISPLAY INVISIBLE (-6140 3885);
FORCEPROP 1 LASTPIN (-6150 3875) BN 30
J 0
(-6162 3883);
DISPLAY 0.489362 (-6162 3883);
PAINT GREEN (-6162 3883);
FORCEPROP 2 LAST CDS_LIB mstr_standard
J 0
(-6100 3875);
DISPLAY 0.723404 (-6100 3875);
PAINT MONO (-6100 3875);
DISPLAY INVISIBLE (-6100 3875);
FORCEPROP 1 LAST BODY_TYPE PLUMBING
J 0
(-6100 3925);
DISPLAY 0.872340 (-6100 3925);
PAINT GREEN (-6100 3925);
DISPLAY INVISIBLE (-6100 3925);
FORCEPROP 1 LAST HDL_TAP TRUE
J 0
(-5775 3750);
DISPLAY 0.872340 (-5775 3750);
DISPLAY INVISIBLE (-5775 3750);
FORCEPROP 1 LAST PATH I82
J 0
(-6102 3875);
DISPLAY 0.872340 (-6102 3875);
PAINT GREEN (-6102 3875);
DISPLAY INVISIBLE (-6102 3875);
FORCEADD TAP..1
(-6100 3825);
FORCEPROP 3 LASTPIN (-6150 3825) SIG_NAME M_D_CPU1_SB_DQ<29>
J 0
(-6140 3835);
DISPLAY 0.659574 (-6140 3835);
PAINT MONO (-6140 3835);
DISPLAY INVISIBLE (-6140 3835);
FORCEPROP 1 LASTPIN (-6150 3825) BN 29
J 0
(-6162 3833);
DISPLAY 0.489362 (-6162 3833);
PAINT GREEN (-6162 3833);
FORCEPROP 2 LAST CDS_LIB mstr_standard
J 0
(-6100 3825);
DISPLAY 0.723404 (-6100 3825);
PAINT MONO (-6100 3825);
DISPLAY INVISIBLE (-6100 3825);
FORCEPROP 1 LAST BODY_TYPE PLUMBING
J 0
(-6100 3875);
DISPLAY 0.872340 (-6100 3875);
PAINT GREEN (-6100 3875);
DISPLAY INVISIBLE (-6100 3875);
FORCEPROP 1 LAST HDL_TAP TRUE
J 0
(-5775 3700);
DISPLAY 0.872340 (-5775 3700);
DISPLAY INVISIBLE (-5775 3700);
FORCEPROP 1 LAST PATH I83
J 0
(-6102 3825);
DISPLAY 0.872340 (-6102 3825);
PAINT GREEN (-6102 3825);
DISPLAY INVISIBLE (-6102 3825);
FORCEADD TAP..1
(-6100 3925);
FORCEPROP 3 LASTPIN (-6150 3925) SIG_NAME M_D_CPU1_SB_DQ<31>
J 0
(-6140 3935);
DISPLAY 0.659574 (-6140 3935);
PAINT MONO (-6140 3935);
DISPLAY INVISIBLE (-6140 3935);
FORCEPROP 1 LASTPIN (-6150 3925) BN 31
J 0
(-6162 3933);
DISPLAY 0.489362 (-6162 3933);
PAINT GREEN (-6162 3933);
FORCEPROP 2 LAST CDS_LIB mstr_standard
J 0
(-6100 3925);
DISPLAY 0.723404 (-6100 3925);
PAINT MONO (-6100 3925);
DISPLAY INVISIBLE (-6100 3925);
FORCEPROP 1 LAST BODY_TYPE PLUMBING
J 0
(-6100 3975);
DISPLAY 0.872340 (-6100 3975);
PAINT GREEN (-6100 3975);
DISPLAY INVISIBLE (-6100 3975);
FORCEPROP 1 LAST HDL_TAP TRUE
J 0
(-5775 3800);
DISPLAY 0.872340 (-5775 3800);
DISPLAY INVISIBLE (-5775 3800);
FORCEPROP 1 LAST PATH I84
J 0
(-6102 3925);
DISPLAY 0.872340 (-6102 3925);
PAINT GREEN (-6102 3925);
DISPLAY INVISIBLE (-6102 3925);
FORCEADD TAP..1
(-6100 4025);
FORCEPROP 3 LASTPIN (-6150 4025) SIG_NAME M_D_CPU1_SA_DQ<0>
J 0
(-6140 4035);
DISPLAY 0.659574 (-6140 4035);
PAINT MONO (-6140 4035);
DISPLAY INVISIBLE (-6140 4035);
FORCEPROP 1 LASTPIN (-6150 4025) BN 0
J 0
(-6162 4033);
DISPLAY 0.489362 (-6162 4033);
PAINT GREEN (-6162 4033);
FORCEPROP 2 LAST CDS_LIB mstr_standard
J 0
(-6100 4025);
DISPLAY 0.723404 (-6100 4025);
PAINT MONO (-6100 4025);
DISPLAY INVISIBLE (-6100 4025);
FORCEPROP 1 LAST BODY_TYPE PLUMBING
J 0
(-6100 4075);
DISPLAY 0.872340 (-6100 4075);
PAINT GREEN (-6100 4075);
DISPLAY INVISIBLE (-6100 4075);
FORCEPROP 1 LAST HDL_TAP TRUE
J 0
(-5775 3900);
DISPLAY 0.872340 (-5775 3900);
DISPLAY INVISIBLE (-5775 3900);
FORCEPROP 1 LAST PATH I85
J 0
(-6102 4025);
DISPLAY 0.872340 (-6102 4025);
PAINT GREEN (-6102 4025);
DISPLAY INVISIBLE (-6102 4025);
FORCEADD TAP..1
(-6100 4125);
FORCEPROP 3 LASTPIN (-6150 4125) SIG_NAME M_D_CPU1_SA_DQ<2>
J 0
(-6140 4135);
DISPLAY 0.659574 (-6140 4135);
PAINT MONO (-6140 4135);
DISPLAY INVISIBLE (-6140 4135);
FORCEPROP 1 LASTPIN (-6150 4125) BN 2
J 0
(-6162 4133);
DISPLAY 0.489362 (-6162 4133);
PAINT GREEN (-6162 4133);
FORCEPROP 2 LAST CDS_LIB mstr_standard
J 0
(-6100 4125);
DISPLAY 0.723404 (-6100 4125);
PAINT MONO (-6100 4125);
DISPLAY INVISIBLE (-6100 4125);
FORCEPROP 1 LAST BODY_TYPE PLUMBING
J 0
(-6100 4175);
DISPLAY 0.872340 (-6100 4175);
PAINT GREEN (-6100 4175);
DISPLAY INVISIBLE (-6100 4175);
FORCEPROP 1 LAST HDL_TAP TRUE
J 0
(-5775 4000);
DISPLAY 0.872340 (-5775 4000);
DISPLAY INVISIBLE (-5775 4000);
FORCEPROP 1 LAST PATH I86
J 0
(-6102 4125);
DISPLAY 0.872340 (-6102 4125);
PAINT GREEN (-6102 4125);
DISPLAY INVISIBLE (-6102 4125);
FORCEADD TAP..1
(-6100 4075);
FORCEPROP 3 LASTPIN (-6150 4075) SIG_NAME M_D_CPU1_SA_DQ<1>
J 0
(-6140 4085);
DISPLAY 0.659574 (-6140 4085);
PAINT MONO (-6140 4085);
DISPLAY INVISIBLE (-6140 4085);
FORCEPROP 1 LASTPIN (-6150 4075) BN 1
J 0
(-6162 4083);
DISPLAY 0.489362 (-6162 4083);
PAINT GREEN (-6162 4083);
FORCEPROP 2 LAST CDS_LIB mstr_standard
J 0
(-6100 4075);
DISPLAY 0.723404 (-6100 4075);
PAINT MONO (-6100 4075);
DISPLAY INVISIBLE (-6100 4075);
FORCEPROP 1 LAST BODY_TYPE PLUMBING
J 0
(-6100 4125);
DISPLAY 0.872340 (-6100 4125);
PAINT GREEN (-6100 4125);
DISPLAY INVISIBLE (-6100 4125);
FORCEPROP 1 LAST HDL_TAP TRUE
J 0
(-5775 3950);
DISPLAY 0.872340 (-5775 3950);
DISPLAY INVISIBLE (-5775 3950);
FORCEPROP 1 LAST PATH I87
J 0
(-6102 4075);
DISPLAY 0.872340 (-6102 4075);
PAINT GREEN (-6102 4075);
DISPLAY INVISIBLE (-6102 4075);
FORCEADD TAP..1
(-6100 4175);
FORCEPROP 3 LASTPIN (-6150 4175) SIG_NAME M_D_CPU1_SA_DQ<3>
J 0
(-6140 4185);
DISPLAY 0.659574 (-6140 4185);
PAINT MONO (-6140 4185);
DISPLAY INVISIBLE (-6140 4185);
FORCEPROP 1 LASTPIN (-6150 4175) BN 3
J 0
(-6162 4183);
DISPLAY 0.489362 (-6162 4183);
PAINT GREEN (-6162 4183);
FORCEPROP 2 LAST CDS_LIB mstr_standard
J 0
(-6100 4175);
DISPLAY 0.723404 (-6100 4175);
PAINT MONO (-6100 4175);
DISPLAY INVISIBLE (-6100 4175);
FORCEPROP 1 LAST BODY_TYPE PLUMBING
J 0
(-6100 4225);
DISPLAY 0.872340 (-6100 4225);
PAINT GREEN (-6100 4225);
DISPLAY INVISIBLE (-6100 4225);
FORCEPROP 1 LAST HDL_TAP TRUE
J 0
(-5775 4050);
DISPLAY 0.872340 (-5775 4050);
DISPLAY INVISIBLE (-5775 4050);
FORCEPROP 1 LAST PATH I88
J 0
(-6102 4175);
DISPLAY 0.872340 (-6102 4175);
PAINT GREEN (-6102 4175);
DISPLAY INVISIBLE (-6102 4175);
FORCEADD OFFPAGE..1
(-8250 3275);
FORCEPROP 2 LAST $XR0 40 
J 0
(-8501 3275);
DISPLAY 0.638298 (-8501 3275);
PAINT MONO (-8501 3275);
FORCEPROP 2 LAST CDS_LIB mstr_standard
J 0
(-8250 3275);
DISPLAY 0.808511 (-8250 3275);
DISPLAY INVISIBLE (-8250 3275);
FORCEPROP 1 LAST OFFPAGE TRUE
J 0
(-7925 3150);
DISPLAY 0.872340 (-7925 3150);
PAINT GREEN (-7925 3150);
DISPLAY INVISIBLE (-7925 3150);
FORCEPROP 1 LAST COMMENT_BODY TRUE
J 0
(-8125 3175);
DISPLAY 0.872340 (-8125 3175);
PAINT GREEN (-8125 3175);
DISPLAY INVISIBLE (-8125 3175);
FORCEPROP 2 LAST PATH I9
J 0
(-8550 3325);
DISPLAY 1.021277 (-8550 3325);
DISPLAY INVISIBLE (-8550 3325);
FORCEADD OFFPAGE..5
(-7300 1600);
FORCEPROP 2 LAST $XR0 101 
J 0
(-7555 1600);
DISPLAY 0.638298 (-7555 1600);
PAINT MONO (-7555 1600);
FORCEPROP 2 LAST BOM_COST MEM
J 0
(-7375 1675);
DISPLAY 0.808511 (-7375 1675);
DISPLAY INVISIBLE (-7375 1675);
FORCEPROP 2 LAST CDS_LIB mstr_standard
J 0
(-7300 1600);
DISPLAY 0.808511 (-7300 1600);
DISPLAY INVISIBLE (-7300 1600);
FORCEPROP 1 LAST OFFPAGE TRUE
J 0
(-6975 1475);
DISPLAY 0.872340 (-6975 1475);
PAINT GREEN (-6975 1475);
DISPLAY INVISIBLE (-6975 1475);
FORCEPROP 1 LAST COMMENT_BODY TRUE
J 0
(-7200 1525);
DISPLAY 0.872340 (-7200 1525);
PAINT GREEN (-7200 1525);
DISPLAY INVISIBLE (-7200 1525);
FORCEPROP 2 LAST PATH I96
J 0
(-7550 1650);
DISPLAY 1.021277 (-7550 1650);
DISPLAY INVISIBLE (-7550 1650);
FORCEADD OFFPAGE..3
(-5425 3975);
FORCEPROP 2 LAST $XR0 40 
J 0
(-5211 3975);
DISPLAY 0.638298 (-5211 3975);
PAINT MONO (-5211 3975);
FORCEPROP 2 LAST CDS_LIB mstr_standard
J 0
(-5425 3975);
DISPLAY 0.723404 (-5425 3975);
PAINT MONO (-5425 3975);
DISPLAY INVISIBLE (-5425 3975);
FORCEPROP 1 LAST OFFPAGE TRUE
J 0
(-5100 3850);
DISPLAY 0.872340 (-5100 3850);
PAINT GREEN (-5100 3850);
DISPLAY INVISIBLE (-5100 3850);
FORCEPROP 1 LAST COMMENT_BODY TRUE
J 0
(-5475 3875);
DISPLAY 0.872340 (-5475 3875);
PAINT GREEN (-5475 3875);
DISPLAY INVISIBLE (-5475 3875);
FORCEPROP 2 LAST PATH I97
J 0
(-5200 4025);
DISPLAY 1.021277 (-5200 4025);
DISPLAY INVISIBLE (-5200 4025);
FORCEADD QUANTA_TITLE_BLOCK_C..1
(-100 100);
FORCEPROP 0 LAST CDS_CON_LAST_MODIFIED Thu Sep 14 16:12:11 2023
J 0
(-1985 115);
DISPLAY INVISIBLE (-1985 115);
FORCEPROP 1 LAST CUSTOM_TXT_CDS <CON_LAST_MODIFIED>
J 0
(-1985 115);
DISPLAY 0.978723 (-1985 115);
FORCEPROP 2 LAST CUSTOM_TXT_CDS <XR_PAGE_TITLE>
J 0
(-7990 5350);
DISPLAY 0.638298 (-7990 5350);
PAINT PINK (-7990 5350);
DISPLAY INVISIBLE (-7990 5350);
FORCEPROP 1 LAST CUSTOM_TXT_CDS <NAME_2>
J 0
(-3275 150);
FORCEPROP 1 LAST CUSTOM_TXT_CDS <NAME_1>
J 0
(-3275 275);
FORCEPROP 1 LAST CUSTOM_TXT_CDS <Q_NUMBER>
J 0
(-1503 203);
DISPLAY 1.212766 (-1503 203);
FORCEPROP 1 LAST CUSTOM_TXT_CDS <Q_PROJ>
J 0
(-2482 202);
DISPLAY 1.212766 (-2482 202);
FORCEPROP 1 LAST CUSTOM_TXT_CDS <Q_REV>
J 0
(-284 203);
DISPLAY 1.212766 (-284 203);
FORCEPROP 1 LAST CUSTOM_TXT_CDS <CON_PAGE_NUM> OF <CON_TOTAL_PAGES>
J 0
(-546 118);
DISPLAY 0.978723 (-546 118);
FORCEPROP 1 LAST Q_TITLE DDR5 - CPU1 CHD
J 0
(-9425 150);
DISPLAY 2.446809 (-9425 150);
PAINT GREEN (-9425 150);
FORCEPROP 2 LAST CDS_LIB pure_quanta
J 0
(-100 100);
DISPLAY INVISIBLE (-100 100);
FORCEPROP 1 LAST CDS_LMAN_SYM_OUTLINE -9475,6775,100,-125
J 0
(-100 100);
DISPLAY 0.468085 (-100 100);
PAINT GREEN (-100 100);
DISPLAY INVISIBLE (-100 100);
FORCEPROP 2 LAST PAGE_BORDER TRUE
J 0
(-7990 5350);
DISPLAY 0.638298 (-7990 5350);
PAINT PINK (-7990 5350);
DISPLAY INVISIBLE (-7990 5350);
FORCEPROP 2 LAST CDS_XR_PAGE_TITLE CR-101 : @T6G_MB_LIB.T6G(SCH_1):PAGE101
J 0
(-7990 5350);
DISPLAY 0.638298 (-7990 5350);
PAINT PINK (-7990 5350);
DISPLAY INVISIBLE (-7990 5350);
FORCEPROP 1 LAST Q_DEPT BU9
J 1
(-3863 149);
DISPLAY 1.957447 (-3863 149);
PAINT GREEN (-3863 149);
DISPLAY INVISIBLE (-3863 149);
FORCEPROP 1 LAST COMMENT_BODY TRUE
J 0
(-88 87);
DISPLAY 0.978723 (-88 87);
PAINT GREEN (-88 87);
DISPLAY INVISIBLE (-88 87);
FORCEADD DNS..2
(-8450 2475);
PAINT RED (-8450 2475);
FORCEPROP 2 LAST CDS_LIB mstr_misc
J 0
(-8450 2475);
DISPLAY INVISIBLE (-8450 2475);
FORCEPROP 1 LAST COMMENT_BODY TRUE
R 1
J 0
(-8375 2250);
DISPLAY 0.872340 (-8375 2250);
PAINT PEACH (-8375 2250);
DISPLAY INVISIBLE (-8375 2250);
WIRE 17 -1 (-7850 4200)(-7850 4225);
WIRE 17 -1 (-7850 4200)(-7850 4150);
WIRE 17 -1 (-7850 4225)(-8350 4225);
FORCEPROP 2 LAST SIG_NAME M_D_CPU1_SA_CB<7:0>
J 0
(-8300 4235);
DISPLAY 0.489362 (-8300 4235);
WIRE 17 -1 (-7850 4100)(-7850 4050);
WIRE 17 -1 (-7850 4100)(-7850 4150);
WIRE 17 -1 (-7850 4000)(-7850 4050);
WIRE 17 -1 (-7850 3950)(-7850 4000);
WIRE 17 -1 (-7850 3900)(-7850 3950);
WIRE 17 -1 (-7850 3850)(-7850 3900);
WIRE 17 -1 (-7850 3750)(-7850 3775);
WIRE 17 -1 (-7850 3750)(-7850 3700);
WIRE 17 -1 (-7850 3775)(-8350 3775);
FORCEPROP 2 LAST SIG_NAME M_D_CPU1_SB_CB<7:0>
J 0
(-8300 3785);
DISPLAY 0.489362 (-8300 3785);
WIRE 17 -1 (-7850 5300)(-7850 5350);
WIRE 17 -1 (-7850 5350)(-7850 5400);
WIRE 17 -1 (-7850 5400)(-7850 5450);
WIRE 17 -1 (-7850 5450)(-7850 5500);
WIRE 17 -1 (-7850 5500)(-7850 5550);
WIRE 17 -1 (-7850 5550)(-7850 5600);
WIRE 17 -1 (-7850 5600)(-7850 5625);
WIRE 17 -1 (-7850 5625)(-8350 5625);
FORCEPROP 2 LAST SIG_NAME M_D_CPU1_SA_CA<6:0>
J 0
(-8335 5635);
DISPLAY 0.489362 (-8335 5635);
WIRE 17 -1 (-7850 4900)(-7850 4950);
WIRE 17 -1 (-7850 4950)(-7850 5000);
WIRE 17 -1 (-7850 5000)(-7850 5050);
WIRE 17 -1 (-7850 5050)(-7850 5100);
WIRE 17 -1 (-7850 5100)(-7850 5150);
WIRE 17 -1 (-7850 5150)(-7850 5200);
WIRE 17 -1 (-7850 5200)(-7850 5225);
WIRE 17 -1 (-7850 5225)(-8350 5225);
FORCEPROP 2 LAST SIG_NAME M_D_CPU1_SB_CA<6:0>
J 0
(-8335 5235);
DISPLAY 0.489362 (-8335 5235);
WIRE 17 -1 (-7850 3650)(-7850 3700);
WIRE 17 -1 (-7850 3650)(-7850 3600);
WIRE 17 -1 (-7850 3550)(-7850 3600);
WIRE 17 -1 (-7850 3500)(-7850 3550);
WIRE 17 -1 (-7850 3450)(-7850 3500);
WIRE 17 -1 (-7850 3400)(-7850 3450);
WIRE 17 -1 (-6050 5600)(-6050 5550);
WIRE 17 -1 (-6050 5625)(-6050 5600);
WIRE 17 -1 (-6050 5550)(-6050 5500);
WIRE 17 -1 (-6050 5500)(-6050 5450);
WIRE 17 -1 (-6050 5625)(-5475 5625);
FORCEPROP 2 LAST SIG_NAME M_D_CPU1_SA_DQ<31:0>
J 0
(-5985 5635);
DISPLAY 0.489362 (-5985 5635);
WIRE 17 -1 (-6050 5450)(-6050 5400);
WIRE 17 -1 (-6050 5400)(-6050 5350);
WIRE 17 -1 (-6050 5350)(-6050 5300);
WIRE 17 -1 (-6050 5300)(-6050 5250);
WIRE 17 -1 (-6050 5250)(-6050 5200);
WIRE 17 -1 (-6050 5200)(-6050 5150);
WIRE 17 -1 (-6050 5150)(-6050 5100);
WIRE 17 -1 (-6050 5100)(-6050 5050);
WIRE 17 -1 (-6050 5050)(-6050 5000);
WIRE 17 -1 (-6050 5000)(-6050 4950);
WIRE 17 -1 (-6050 4950)(-6050 4900);
WIRE 17 -1 (-6050 4900)(-6050 4850);
WIRE 17 -1 (-6050 4800)(-6050 4850);
WIRE 17 -1 (-6050 4750)(-6050 4800);
WIRE 17 -1 (-6050 4700)(-6050 4750);
WIRE 17 -1 (-6050 4650)(-6050 4700);
WIRE 17 -1 (-6050 4650)(-6050 4600);
WIRE 17 -1 (-6050 4600)(-6050 4550);
WIRE 17 -1 (-6050 4550)(-6050 4500);
WIRE 17 -1 (-6050 4500)(-6050 4450);
WIRE 17 -1 (-6050 4450)(-6050 4400);
WIRE 17 -1 (-6050 4400)(-6050 4350);
WIRE 17 -1 (-6050 4350)(-6050 4300);
WIRE 17 -1 (-6050 4300)(-6050 4250);
WIRE 17 -1 (-6050 4200)(-6050 4250);
WIRE 17 -1 (-6050 4150)(-6050 4200);
WIRE 17 -1 (-6050 4100)(-6050 4150);
WIRE 17 -1 (-6050 4050)(-6050 4100);
WIRE 17 -1 (-6050 3975)(-6050 3950);
WIRE 17 -1 (-6050 3975)(-5475 3975);
FORCEPROP 2 LAST SIG_NAME M_D_CPU1_SB_DQ<31:0>
J 0
(-5985 3985);
DISPLAY 0.489362 (-5985 3985);
WIRE 17 -1 (-6050 3950)(-6050 3900);
WIRE 17 -1 (-6050 3900)(-6050 3850);
WIRE 17 -1 (-6050 3850)(-6050 3800);
WIRE 17 -1 (-6050 3800)(-6050 3750);
WIRE 17 -1 (-6050 3750)(-6050 3700);
WIRE 17 -1 (-6050 3700)(-6050 3650);
WIRE 17 -1 (-6050 3650)(-6050 3600);
WIRE 17 -1 (-6050 3600)(-6050 3550);
WIRE 17 -1 (-6050 3550)(-6050 3500);
WIRE 17 -1 (-6050 3500)(-6050 3450);
WIRE 17 -1 (-6050 3450)(-6050 3400);
WIRE 17 -1 (-6050 3400)(-6050 3350);
WIRE 17 -1 (-6050 3350)(-6050 3300);
WIRE 17 -1 (-6050 3300)(-6050 3250);
WIRE 17 -1 (-6050 3250)(-6050 3200);
WIRE 17 -1 (-6050 3150)(-6050 3200);
WIRE 17 -1 (-6050 3100)(-6050 3150);
WIRE 17 -1 (-6050 3050)(-6050 3100);
WIRE 17 -1 (-6050 3000)(-6050 3050);
WIRE 17 -1 (-6050 3000)(-6050 2950);
WIRE 17 -1 (-6050 2950)(-6050 2900);
WIRE 17 -1 (-6050 2900)(-6050 2850);
WIRE 17 -1 (-6050 2850)(-6050 2800);
WIRE 17 -1 (-6050 2800)(-6050 2750);
WIRE 17 -1 (-6050 2750)(-6050 2700);
WIRE 17 -1 (-6050 2700)(-6050 2650);
WIRE 17 -1 (-6050 2650)(-6050 2600);
WIRE 17 -1 (-6050 2550)(-6050 2600);
WIRE 17 -1 (-6050 2500)(-6050 2550);
WIRE 17 -1 (-6050 2450)(-6050 2500);
WIRE 17 -1 (-6050 2400)(-6050 2450);
WIRE 17 -1 (-3225 4600)(-3225 4500);
WIRE 17 -1 (-3225 4700)(-3225 4600);
WIRE 17 -1 (-3225 4500)(-3225 4400);
WIRE 17 -1 (-3225 4400)(-3225 4300);
WIRE 17 -1 (-3225 4725)(-3225 4700);
WIRE 17 -1 (-3225 4725)(-2525 4725);
FORCEPROP 2 LAST SIG_NAME M_D_CPU1_SA_DQS_DN<9:0>
J 0
(-3160 4735);
DISPLAY 0.489362 (-3160 4735);
WIRE 17 -1 (-3425 4550)(-3425 4450);
WIRE 17 -1 (-3425 4650)(-3425 4550);
WIRE 17 -1 (-3425 4450)(-3425 4350);
WIRE 17 -1 (-3425 4250)(-3425 4350);
WIRE 17 -1 (-3425 4750)(-3425 4650);
WIRE 17 -1 (-3425 4775)(-3425 4750);
WIRE 17 -1 (-3425 4150)(-3425 4250);
WIRE 17 -1 (-3425 4050)(-3425 4150);
WIRE 17 -1 (-3425 4775)(-2525 4775);
FORCEPROP 2 LAST SIG_NAME M_D_CPU1_SA_DQS_DP<9:0>
J 0
(-3160 4785);
DISPLAY 0.489362 (-3160 4785);
WIRE 17 -1 (-3425 3700)(-3425 3600);
WIRE 17 -1 (-3425 3725)(-3425 3700);
WIRE 17 -1 (-3425 3600)(-3425 3500);
WIRE 17 -1 (-3425 3500)(-3425 3400);
WIRE 17 -1 (-3425 3725)(-2525 3725);
FORCEPROP 2 LAST SIG_NAME M_D_CPU1_SB_DQS_DP<9:0>
J 0
(-3160 3735);
DISPLAY 0.489362 (-3160 3735);
WIRE 17 -1 (-3225 3650)(-3225 3550);
WIRE 17 -1 (-3225 3675)(-3225 3650);
WIRE 17 -1 (-3225 3550)(-3225 3450);
WIRE 17 -1 (-3225 3450)(-3225 3350);
WIRE 17 -1 (-3225 3675)(-2525 3675);
FORCEPROP 2 LAST SIG_NAME M_D_CPU1_SB_DQS_DN<9:0>
J 0
(-3160 3685);
DISPLAY 0.489362 (-3160 3685);
WIRE 17 -1 (-3425 3400)(-3425 3300);
WIRE 17 -1 (-3225 3900)(-3225 3800);
WIRE 17 -1 (-3225 4000)(-3225 3900);
WIRE 17 -1 (-3225 4000)(-3225 4100);
WIRE 17 -1 (-3225 4100)(-3225 4200);
WIRE 17 -1 (-3225 4200)(-3225 4300);
WIRE 17 -1 (-3425 3950)(-3425 3850);
WIRE 17 -1 (-3425 4050)(-3425 3950);
WIRE 17 -1 (-3225 2850)(-3225 2750);
WIRE 17 -1 (-3225 2950)(-3225 2850);
WIRE 17 -1 (-3225 2950)(-3225 3050);
WIRE 17 -1 (-3225 3050)(-3225 3150);
WIRE 17 -1 (-3225 3150)(-3225 3250);
WIRE 17 -1 (-3225 3350)(-3225 3250);
WIRE 17 -1 (-3425 2900)(-3425 2800);
WIRE 17 -1 (-3425 3000)(-3425 2900);
WIRE 17 -1 (-3425 3000)(-3425 3100);
WIRE 17 -1 (-3425 3100)(-3425 3200);
WIRE 17 -1 (-3425 3200)(-3425 3300);
WIRE 16 -1 (-6525 1250)(-6525 1325);
WIRE 16 -1 (-8750 3225)(-8750 3300);
WIRE 16 -1 (-8475 2575)(-8475 2600);
WIRE 16 -1 (-7550 3375)(-7750 3375);
WIRE 16 -1 (-7550 3075)(-8725 3075);
FORCEPROP 2 LAST SIG_NAME PD_CHD_CPU1_DIMM_SAA
J 0
(-8700 3085);
DISPLAY 0.489362 (-8700 3085);
WIRE 16 -1 (-8750 3500)(-8750 3525);
WIRE 16 -1 (-8750 3525)(-8650 3525);
WIRE 16 -1 (-8650 3525)(-8650 3125);
WIRE 16 -1 (-8650 3550)(-8650 3525);
WIRE 16 -1 (-8650 3125)(-7550 3125);
WIRE 16 -1 (-8350 3025)(-8325 3025);
WIRE 16 -1 (-8350 2900)(-8350 3025);
WIRE 16 -1 (-8350 2900)(-8850 2900);
FORCEPROP 2 LAST SIG_NAME I3C_SPD_DDRAF_CPU1_SDA
J 0
(-8860 2910);
DISPLAY 0.489362 (-8860 2910);
WIRE 16 -1 (-7550 3025)(-8125 3025);
FORCEPROP 2 LAST SIG_NAME I3C_SPD_DDRD_CPU1_SDA
J 0
(-8035 3035);
DISPLAY 0.446809 (-8035 3035);
FORCEPROP 2 LASTPROP $XRERR UNIQUE?
J 0
(-8275 3035);
DISPLAY 0.638298 (-8275 3035);
PAINT MONO (-8275 3035);
DISPLAY INVISIBLE (-8275 3035);
WIRE 16 -1 (-7950 2800)(-8425 2800);
FORCEPROP 2 LAST SIG_NAME I3C_SPD_DDRAF_CPU1_SCL
J 0
(-8485 2810);
DISPLAY 0.489362 (-8485 2810);
WIRE 16 -1 (-7550 3225)(-8200 3225);
FORCEPROP 2 LAST SIG_NAME M_D_CPU1_ALERT_N
J 0
(-8185 3235);
DISPLAY 0.489362 (-8185 3235);
WIRE 16 -1 (-7550 3275)(-8200 3275);
FORCEPROP 2 LAST SIG_NAME M_D_CPU1_RESET_N
J 0
(-8185 3285);
DISPLAY 0.489362 (-8185 3285);
WIRE 16 -1 (-7550 2975)(-7650 2975);
FORCEPROP 2 LAST SIG_NAME I3C_SPD_DDRD_CPU1_SCL
J 0
(-8035 2985);
DISPLAY 0.446809 (-8035 2985);
FORCEPROP 2 LASTPROP $XRERR UNIQUE?
J 0
(-8275 2985);
DISPLAY 0.638298 (-8275 2985);
PAINT MONO (-8275 2985);
DISPLAY INVISIBLE (-8275 2985);
WIRE 16 -1 (-7650 2975)(-7650 2800);
WIRE 16 -1 (-7650 2800)(-7750 2800);
WIRE 16 -1 (-7550 3425)(-7750 3425);
WIRE 16 -1 (-6150 3175)(-6350 3175);
WIRE 16 -1 (-6150 3225)(-6350 3225);
WIRE 16 -1 (-8475 2375)(-8475 2325);
WIRE 16 -1 (-8275 2325)(-8475 2325);
WIRE 16 -1 (-8475 2325)(-8500 2325);
WIRE 16 -1 (-8275 2325)(-8275 2725);
WIRE 16 -1 (-7550 2725)(-8275 2725);
FORCEPROP 2 LAST SIG_NAME PWRGD_CHD_CPU1_DIMM
J 0
(-8160 2735);
DISPLAY 0.489362 (-8160 2735);
FORCEPROP 2 LASTPROP $XRERR UNIQUE?
J 0
(-8400 2735);
DISPLAY 0.638298 (-8400 2735);
PAINT MONO (-8400 2735);
DISPLAY INVISIBLE (-8400 2735);
WIRE 16 -1 (-9050 2325)(-8700 2325);
FORCEPROP 2 LAST SIG_NAME PWRGD_CHAF_CPU1
J 0
(-9060 2335);
DISPLAY 0.489362 (-9060 2335);
WIRE 16 -1 (-7550 2175)(-8350 2175);
FORCEPROP 2 LAST SIG_NAME M_D_CPU1_SA_RSP<0>
J 0
(-8300 2185);
DISPLAY 0.489362 (-8300 2185);
WIRE 16 -1 (-7550 2125)(-8350 2125);
FORCEPROP 2 LAST SIG_NAME M_D_CPU1_SB_RSP<0>
J 0
(-8300 2135);
DISPLAY 0.489362 (-8300 2135);
WIRE 16 -1 (-2325 6000)(-2200 6000);
WIRE 16 -1 (-2325 6000)(-2325 5900);
WIRE 16 -1 (-2325 6000)(-2900 6000);
WIRE 16 -1 (-2200 5400)(-2200 6000);
WIRE 16 -1 (-1900 5400)(-2200 5400);
WIRE 16 -1 (-2200 5350)(-2200 5400);
WIRE 16 -1 (-2900 5900)(-2900 6000);
WIRE 16 -1 (-2900 6000)(-2900 6075);
WIRE 16 -1 (-1900 5350)(-2200 5350);
WIRE 16 -1 (-2200 5350)(-2200 5300);
WIRE 16 -1 (-2200 5300)(-1900 5300);
WIRE 16 -1 (-2325 5575)(-2325 5700);
WIRE 16 -1 (-2325 5575)(-2900 5575);
WIRE 16 -1 (-2900 5575)(-2900 5700);
WIRE 16 -1 (-2900 5575)(-2900 5500);
WIRE 16 -1 (-400 2250)(-400 2150);
WIRE 16 -1 (-400 2300)(-400 2250);
WIRE 16 -1 (-400 2250)(-700 2250);
WIRE 16 -1 (-400 2150)(-400 2100);
WIRE 16 -1 (-400 2150)(-700 2150);
WIRE 16 -1 (-400 2100)(-400 2050);
WIRE 16 -1 (-400 2100)(-700 2100);
WIRE 16 -1 (-400 2350)(-400 2300);
WIRE 16 -1 (-400 2300)(-700 2300);
WIRE 16 -1 (-400 2400)(-400 2350);
WIRE 16 -1 (-400 2350)(-700 2350);
WIRE 16 -1 (-400 2050)(-700 2050);
WIRE 16 -1 (-400 2050)(-400 1850);
WIRE 16 -1 (-400 2450)(-400 2400);
WIRE 16 -1 (-400 2400)(-700 2400);
WIRE 16 -1 (-400 2500)(-400 2450);
WIRE 16 -1 (-400 2450)(-700 2450);
WIRE 16 -1 (-400 2550)(-400 2500);
WIRE 16 -1 (-400 2500)(-700 2500);
WIRE 16 -1 (-400 2600)(-400 2550);
WIRE 16 -1 (-400 2550)(-700 2550);
WIRE 16 -1 (-400 2650)(-400 2600);
WIRE 16 -1 (-400 2600)(-700 2600);
WIRE 16 -1 (-400 2700)(-400 2650);
WIRE 16 -1 (-400 2650)(-700 2650);
WIRE 16 -1 (-400 2750)(-400 2700);
WIRE 16 -1 (-400 2700)(-700 2700);
WIRE 16 -1 (-400 2800)(-400 2750);
WIRE 16 -1 (-400 2750)(-700 2750);
WIRE 16 -1 (-400 2850)(-400 2800);
WIRE 16 -1 (-400 2800)(-700 2800);
WIRE 16 -1 (-400 2900)(-400 2850);
WIRE 16 -1 (-400 2850)(-700 2850);
WIRE 16 -1 (-400 2950)(-400 2900);
WIRE 16 -1 (-400 2900)(-700 2900);
WIRE 16 -1 (-400 3000)(-400 2950);
WIRE 16 -1 (-400 2950)(-700 2950);
WIRE 16 -1 (-400 3050)(-400 3000);
WIRE 16 -1 (-400 3000)(-700 3000);
WIRE 16 -1 (-400 3100)(-400 3050);
WIRE 16 -1 (-400 3050)(-700 3050);
WIRE 16 -1 (-400 3150)(-400 3100);
WIRE 16 -1 (-400 3100)(-700 3100);
WIRE 16 -1 (-400 3200)(-400 3150);
WIRE 16 -1 (-400 3150)(-700 3150);
WIRE 16 -1 (-400 3250)(-400 3200);
WIRE 16 -1 (-400 3200)(-700 3200);
WIRE 16 -1 (-400 3300)(-400 3250);
WIRE 16 -1 (-400 3250)(-700 3250);
WIRE 16 -1 (-400 3350)(-400 3300);
WIRE 16 -1 (-400 3300)(-700 3300);
WIRE 16 -1 (-400 3400)(-400 3350);
WIRE 16 -1 (-400 3350)(-700 3350);
WIRE 16 -1 (-400 3450)(-400 3400);
WIRE 16 -1 (-400 3400)(-700 3400);
WIRE 16 -1 (-400 3500)(-400 3450);
WIRE 16 -1 (-400 3450)(-700 3450);
WIRE 16 -1 (-400 3550)(-400 3500);
WIRE 16 -1 (-400 3500)(-700 3500);
WIRE 16 -1 (-400 3600)(-400 3550);
WIRE 16 -1 (-400 3550)(-700 3550);
WIRE 16 -1 (-400 3650)(-400 3600);
WIRE 16 -1 (-400 3600)(-700 3600);
WIRE 16 -1 (-400 3700)(-400 3650);
WIRE 16 -1 (-400 3650)(-700 3650);
WIRE 16 -1 (-400 3750)(-400 3700);
WIRE 16 -1 (-400 3700)(-700 3700);
WIRE 16 -1 (-400 3800)(-400 3750);
WIRE 16 -1 (-400 3750)(-700 3750);
WIRE 16 -1 (-400 3850)(-400 3800);
WIRE 16 -1 (-400 3800)(-700 3800);
WIRE 16 -1 (-400 3900)(-400 3850);
WIRE 16 -1 (-400 3850)(-700 3850);
WIRE 16 -1 (-400 3950)(-400 3900);
WIRE 16 -1 (-400 3900)(-700 3900);
WIRE 16 -1 (-400 4000)(-400 3950);
WIRE 16 -1 (-400 3950)(-700 3950);
WIRE 16 -1 (-400 4050)(-400 4000);
WIRE 16 -1 (-400 4000)(-700 4000);
WIRE 16 -1 (-400 4100)(-400 4050);
WIRE 16 -1 (-400 4050)(-700 4050);
WIRE 16 -1 (-400 4150)(-400 4100);
WIRE 16 -1 (-400 4100)(-700 4100);
WIRE 16 -1 (-400 4200)(-400 4150);
WIRE 16 -1 (-400 4150)(-700 4150);
WIRE 16 -1 (-400 4250)(-400 4200);
WIRE 16 -1 (-400 4200)(-700 4200);
WIRE 16 -1 (-400 4300)(-400 4250);
WIRE 16 -1 (-400 4250)(-700 4250);
WIRE 16 -1 (-400 4350)(-400 4300);
WIRE 16 -1 (-400 4300)(-700 4300);
WIRE 16 -1 (-400 4400)(-400 4350);
WIRE 16 -1 (-400 4350)(-700 4350);
WIRE 16 -1 (-400 4450)(-400 4400);
WIRE 16 -1 (-400 4400)(-700 4400);
WIRE 16 -1 (-400 4500)(-400 4450);
WIRE 16 -1 (-400 4450)(-700 4450);
WIRE 16 -1 (-400 4550)(-400 4500);
WIRE 16 -1 (-400 4500)(-700 4500);
WIRE 16 -1 (-400 4600)(-400 4550);
WIRE 16 -1 (-400 4550)(-700 4550);
WIRE 16 -1 (-400 4650)(-400 4600);
WIRE 16 -1 (-400 4600)(-700 4600);
WIRE 16 -1 (-400 4700)(-400 4650);
WIRE 16 -1 (-400 4650)(-700 4650);
WIRE 16 -1 (-400 4750)(-400 4700);
WIRE 16 -1 (-400 4700)(-700 4700);
WIRE 16 -1 (-400 4800)(-400 4750);
WIRE 16 -1 (-400 4750)(-700 4750);
WIRE 16 -1 (-400 4850)(-400 4800);
WIRE 16 -1 (-400 4800)(-700 4800);
WIRE 16 -1 (-400 4900)(-400 4850);
WIRE 16 -1 (-400 4850)(-700 4850);
WIRE 16 -1 (-400 4950)(-400 4900);
WIRE 16 -1 (-400 4900)(-700 4900);
WIRE 16 -1 (-400 5000)(-400 4950);
WIRE 16 -1 (-400 4950)(-700 4950);
WIRE 16 -1 (-400 5050)(-400 5000);
WIRE 16 -1 (-400 5000)(-700 5000);
WIRE 16 -1 (-400 5100)(-400 5050);
WIRE 16 -1 (-400 5050)(-700 5050);
WIRE 16 -1 (-400 5150)(-400 5100);
WIRE 16 -1 (-400 5100)(-700 5100);
WIRE 16 -1 (-400 5200)(-400 5150);
WIRE 16 -1 (-400 5150)(-700 5150);
WIRE 16 -1 (-400 5250)(-400 5200);
WIRE 16 -1 (-400 5200)(-700 5200);
WIRE 16 -1 (-400 5300)(-400 5250);
WIRE 16 -1 (-400 5250)(-700 5250);
WIRE 16 -1 (-400 5350)(-400 5300);
WIRE 16 -1 (-400 5300)(-700 5300);
WIRE 16 -1 (-400 5400)(-400 5350);
WIRE 16 -1 (-400 5350)(-700 5350);
WIRE 16 -1 (-400 5400)(-700 5400);
WIRE 16 -1 (-1900 5250)(-2200 5250);
WIRE 16 -1 (-2200 5250)(-2200 5200);
WIRE 16 -1 (-1900 5200)(-2200 5200);
WIRE 16 -1 (-2200 5200)(-2200 5150);
WIRE 16 -1 (-1900 5150)(-2200 5150);
WIRE 16 -1 (-2200 5150)(-2200 5100);
WIRE 16 -1 (-1900 5100)(-2200 5100);
WIRE 16 -1 (-2200 5100)(-2200 5050);
WIRE 16 -1 (-1900 5050)(-2200 5050);
WIRE 16 -1 (-2200 5050)(-2200 5000);
WIRE 16 -1 (-1900 5000)(-2200 5000);
WIRE 16 -1 (-2200 5000)(-2200 4950);
WIRE 16 -1 (-1900 4950)(-2200 4950);
WIRE 16 -1 (-2200 4950)(-2200 4900);
WIRE 16 -1 (-1900 4900)(-2200 4900);
WIRE 16 -1 (-2200 4900)(-2200 4850);
WIRE 16 -1 (-1900 4850)(-2200 4850);
WIRE 16 -1 (-2200 4850)(-2200 4800);
WIRE 16 -1 (-1900 4800)(-2200 4800);
WIRE 16 -1 (-2200 4800)(-2200 4750);
WIRE 16 -1 (-1900 4750)(-2200 4750);
WIRE 16 -1 (-2200 4750)(-2200 4700);
WIRE 16 -1 (-1900 4700)(-2200 4700);
WIRE 16 -1 (-2200 4700)(-2200 4650);
WIRE 16 -1 (-1900 4650)(-2200 4650);
WIRE 16 -1 (-2200 4650)(-2200 4600);
WIRE 16 -1 (-1900 4600)(-2200 4600);
WIRE 16 -1 (-2200 4600)(-2200 4550);
WIRE 16 -1 (-1900 4550)(-2200 4550);
WIRE 16 -1 (-2200 4550)(-2200 4500);
WIRE 16 -1 (-1900 4500)(-2200 4500);
WIRE 16 -1 (-2200 4500)(-2200 4450);
WIRE 16 -1 (-1900 4450)(-2200 4450);
WIRE 16 -1 (-2200 4450)(-2200 4400);
WIRE 16 -1 (-1900 4400)(-2200 4400);
WIRE 16 -1 (-2200 4400)(-2200 4350);
WIRE 16 -1 (-1900 4350)(-2200 4350);
WIRE 16 -1 (-2200 4350)(-2200 4300);
WIRE 16 -1 (-1900 4300)(-2200 4300);
WIRE 16 -1 (-2200 4300)(-2200 4250);
WIRE 16 -1 (-1900 4250)(-2200 4250);
WIRE 16 -1 (-2200 4250)(-2200 4200);
WIRE 16 -1 (-1900 4200)(-2200 4200);
WIRE 16 -1 (-2200 4200)(-2200 4150);
WIRE 16 -1 (-1900 4150)(-2200 4150);
WIRE 16 -1 (-2200 4150)(-2200 4100);
WIRE 16 -1 (-1900 4100)(-2200 4100);
WIRE 16 -1 (-2200 4100)(-2200 4050);
WIRE 16 -1 (-1900 4050)(-2200 4050);
WIRE 16 -1 (-2200 4050)(-2200 4000);
WIRE 16 -1 (-1900 4000)(-2200 4000);
WIRE 16 -1 (-2200 4000)(-2200 3950);
WIRE 16 -1 (-1900 3950)(-2200 3950);
WIRE 16 -1 (-2200 3950)(-2200 3900);
WIRE 16 -1 (-1900 3900)(-2200 3900);
WIRE 16 -1 (-2200 3900)(-2200 3850);
WIRE 16 -1 (-1900 3850)(-2200 3850);
WIRE 16 -1 (-2200 3850)(-2200 3800);
WIRE 16 -1 (-1900 3800)(-2200 3800);
WIRE 16 -1 (-2200 3800)(-2200 3750);
WIRE 16 -1 (-1900 3750)(-2200 3750);
WIRE 16 -1 (-2200 3750)(-2200 3700);
WIRE 16 -1 (-1900 3700)(-2200 3700);
WIRE 16 -1 (-2200 3700)(-2200 3650);
WIRE 16 -1 (-1900 3650)(-2200 3650);
WIRE 16 -1 (-2200 3650)(-2200 3600);
WIRE 16 -1 (-1900 3600)(-2200 3600);
WIRE 16 -1 (-2200 3600)(-2200 3550);
WIRE 16 -1 (-1900 3550)(-2200 3550);
WIRE 16 -1 (-2200 3550)(-2200 3500);
WIRE 16 -1 (-1900 3500)(-2200 3500);
WIRE 16 -1 (-2200 3500)(-2200 3450);
WIRE 16 -1 (-1900 3450)(-2200 3450);
WIRE 16 -1 (-2200 3450)(-2200 3400);
WIRE 16 -1 (-1900 3400)(-2200 3400);
WIRE 16 -1 (-2200 3400)(-2200 3350);
WIRE 16 -1 (-1900 3350)(-2200 3350);
WIRE 16 -1 (-2200 3350)(-2200 3300);
WIRE 16 -1 (-1900 3300)(-2200 3300);
WIRE 16 -1 (-2200 3300)(-2200 3250);
WIRE 16 -1 (-1900 3250)(-2200 3250);
WIRE 16 -1 (-2200 3250)(-2200 3200);
WIRE 16 -1 (-1900 3200)(-2200 3200);
WIRE 16 -1 (-2200 3200)(-2200 3150);
WIRE 16 -1 (-1900 3150)(-2200 3150);
WIRE 16 -1 (-2200 3150)(-2200 3100);
WIRE 16 -1 (-1900 3100)(-2200 3100);
WIRE 16 -1 (-2200 3100)(-2200 3050);
WIRE 16 -1 (-1900 3050)(-2200 3050);
WIRE 16 -1 (-2200 3050)(-2200 3000);
WIRE 16 -1 (-1900 3000)(-2200 3000);
WIRE 16 -1 (-2200 3000)(-2200 2950);
WIRE 16 -1 (-1900 2950)(-2200 2950);
WIRE 16 -1 (-2200 2950)(-2200 2900);
WIRE 16 -1 (-1900 2900)(-2200 2900);
WIRE 16 -1 (-2200 2900)(-2200 2850);
WIRE 16 -1 (-1900 2850)(-2200 2850);
WIRE 16 -1 (-2200 2850)(-2200 2800);
WIRE 16 -1 (-1900 2800)(-2200 2800);
WIRE 16 -1 (-2200 2800)(-2200 2750);
WIRE 16 -1 (-1900 2750)(-2200 2750);
WIRE 16 -1 (-2200 2750)(-2200 2700);
WIRE 16 -1 (-1900 2700)(-2200 2700);
WIRE 16 -1 (-2200 2700)(-2200 2650);
WIRE 16 -1 (-1900 2650)(-2200 2650);
WIRE 16 -1 (-2200 2650)(-2200 2600);
WIRE 16 -1 (-1900 2600)(-2200 2600);
WIRE 16 -1 (-2200 2600)(-2200 2550);
WIRE 16 -1 (-1900 2550)(-2200 2550);
WIRE 16 -1 (-2200 2550)(-2200 2500);
WIRE 16 -1 (-1900 2500)(-2200 2500);
WIRE 16 -1 (-2200 2500)(-2200 2450);
WIRE 16 -1 (-1900 2450)(-2200 2450);
WIRE 16 -1 (-2200 2450)(-2200 2400);
WIRE 16 -1 (-1900 2400)(-2200 2400);
WIRE 16 -1 (-2200 2400)(-2200 2350);
WIRE 16 -1 (-1900 2350)(-2200 2350);
WIRE 16 -1 (-2200 2350)(-2200 2300);
WIRE 16 -1 (-1900 2300)(-2200 2300);
WIRE 16 -1 (-2200 2300)(-2200 2250);
WIRE 16 -1 (-1900 2250)(-2200 2250);
WIRE 16 -1 (-2200 2250)(-2200 2200);
WIRE 16 -1 (-1900 2200)(-2200 2200);
WIRE 16 -1 (-2200 2200)(-2200 2150);
WIRE 16 -1 (-1900 2150)(-2200 2150);
WIRE 16 -1 (-2200 2150)(-2200 2050);
WIRE 16 -1 (-3675 3675)(-3525 3675);
WIRE 16 -1 (-3675 3625)(-3325 3625);
WIRE 16 -1 (-3675 4725)(-3525 4725);
WIRE 16 -1 (-3675 4675)(-3325 4675);
WIRE 16 -1 (-3525 4625)(-3675 4625);
WIRE 16 -1 (-3675 4575)(-3325 4575);
WIRE 16 -1 (-3675 3425)(-3325 3425);
WIRE 16 -1 (-3525 4525)(-3675 4525);
WIRE 16 -1 (-3525 3375)(-3675 3375);
WIRE 16 -1 (-3675 3325)(-3325 3325);
WIRE 16 -1 (-3325 4375)(-3675 4375);
WIRE 16 -1 (-3675 3275)(-3525 3275);
WIRE 16 -1 (-3675 3225)(-3325 3225);
WIRE 16 -1 (-3675 4325)(-3525 4325);
WIRE 16 -1 (-3675 4275)(-3325 4275);
WIRE 16 -1 (-3525 3175)(-3675 3175);
WIRE 16 -1 (-3675 3125)(-3325 3125);
WIRE 16 -1 (-3525 4225)(-3675 4225);
WIRE 16 -1 (-3325 4175)(-3675 4175);
WIRE 16 -1 (-3525 3075)(-3675 3075);
WIRE 16 -1 (-3675 3025)(-3325 3025);
WIRE 16 -1 (-3525 4125)(-3675 4125);
WIRE 16 -1 (-3675 4075)(-3325 4075);
WIRE 16 -1 (-3525 2975)(-3675 2975);
WIRE 16 -1 (-3675 2925)(-3325 2925);
WIRE 16 -1 (-3525 4025)(-3675 4025);
WIRE 16 -1 (-3675 3975)(-3325 3975);
WIRE 16 -1 (-3675 2875)(-3525 2875);
WIRE 16 -1 (-3675 2825)(-3325 2825);
WIRE 16 -1 (-3675 3925)(-3525 3925);
WIRE 16 -1 (-3675 3875)(-3325 3875);
WIRE 16 -1 (-3525 2775)(-3675 2775);
WIRE 16 -1 (-3675 2725)(-3325 2725);
WIRE 16 -1 (-3525 3825)(-3675 3825);
WIRE 16 -1 (-3675 3775)(-3325 3775);
WIRE 16 -1 (-3525 3475)(-3675 3475);
WIRE 16 -1 (-3675 3525)(-3325 3525);
WIRE 16 -1 (-3525 3575)(-3675 3575);
WIRE 16 -1 (-3525 4425)(-3675 4425);
WIRE 16 -1 (-3675 4475)(-3325 4475);
WIRE 16 -1 (-6350 5575)(-6150 5575);
WIRE 16 -1 (-7550 4725)(-8350 4725);
FORCEPROP 2 LAST SIG_NAME M_D_CPU1_SB_PAR
J 0
(-8300 4735);
DISPLAY 0.489362 (-8300 4735);
WIRE 16 -1 (-7550 4775)(-8350 4775);
FORCEPROP 2 LAST SIG_NAME M_D_CPU1_SA_PAR
J 0
(-8300 4785);
DISPLAY 0.489362 (-8300 4785);
WIRE 16 -1 (-6150 2375)(-6350 2375);
WIRE 16 -1 (-6150 2425)(-6350 2425);
WIRE 16 -1 (-6150 2475)(-6350 2475);
WIRE 16 -1 (-6350 2525)(-6150 2525);
WIRE 16 -1 (-6150 2575)(-6350 2575);
WIRE 16 -1 (-6150 2625)(-6350 2625);
WIRE 16 -1 (-6150 2675)(-6350 2675);
WIRE 16 -1 (-6350 2725)(-6150 2725);
WIRE 16 -1 (-6150 2775)(-6350 2775);
WIRE 16 -1 (-6150 2825)(-6350 2825);
WIRE 16 -1 (-6150 2875)(-6350 2875);
WIRE 16 -1 (-6350 2925)(-6150 2925);
WIRE 16 -1 (-6150 2975)(-6350 2975);
WIRE 16 -1 (-6150 3025)(-6350 3025);
WIRE 16 -1 (-6150 3075)(-6350 3075);
WIRE 16 -1 (-6350 3125)(-6150 3125);
WIRE 16 -1 (-6150 3275)(-6350 3275);
WIRE 16 -1 (-6350 3325)(-6150 3325);
WIRE 16 -1 (-6150 3375)(-6350 3375);
WIRE 16 -1 (-6150 3425)(-6350 3425);
WIRE 16 -1 (-6150 3475)(-6350 3475);
WIRE 16 -1 (-6350 3525)(-6150 3525);
WIRE 16 -1 (-6150 3575)(-6350 3575);
WIRE 16 -1 (-6150 3625)(-6350 3625);
WIRE 16 -1 (-6150 3675)(-6350 3675);
WIRE 16 -1 (-6350 3725)(-6150 3725);
WIRE 16 -1 (-6150 3775)(-6350 3775);
WIRE 16 -1 (-6150 3825)(-6350 3825);
WIRE 16 -1 (-6150 3875)(-6350 3875);
WIRE 16 -1 (-6350 3925)(-6150 3925);
WIRE 16 -1 (-6150 4025)(-6350 4025);
WIRE 16 -1 (-6150 4075)(-6350 4075);
WIRE 16 -1 (-6150 4125)(-6350 4125);
WIRE 16 -1 (-6350 4175)(-6150 4175);
WIRE 16 -1 (-6150 4225)(-6350 4225);
WIRE 16 -1 (-6150 4275)(-6350 4275);
WIRE 16 -1 (-6150 4325)(-6350 4325);
WIRE 16 -1 (-6350 4375)(-6150 4375);
WIRE 16 -1 (-6150 4425)(-6350 4425);
WIRE 16 -1 (-6150 4475)(-6350 4475);
WIRE 16 -1 (-6150 4525)(-6350 4525);
WIRE 16 -1 (-6350 4575)(-6150 4575);
WIRE 16 -1 (-6150 4625)(-6350 4625);
WIRE 16 -1 (-6150 4675)(-6350 4675);
WIRE 16 -1 (-6150 4725)(-6350 4725);
WIRE 16 -1 (-6350 4775)(-6150 4775);
WIRE 16 -1 (-6150 4825)(-6350 4825);
WIRE 16 -1 (-6150 4875)(-6350 4875);
WIRE 16 -1 (-6150 4925)(-6350 4925);
WIRE 16 -1 (-6350 4975)(-6150 4975);
WIRE 16 -1 (-6150 5025)(-6350 5025);
WIRE 16 -1 (-6150 5075)(-6350 5075);
WIRE 16 -1 (-6150 5125)(-6350 5125);
WIRE 16 -1 (-6350 5175)(-6150 5175);
WIRE 16 -1 (-6150 5225)(-6350 5225);
WIRE 16 -1 (-6150 5275)(-6350 5275);
WIRE 16 -1 (-6150 5325)(-6350 5325);
WIRE 16 -1 (-6350 5375)(-6150 5375);
WIRE 16 -1 (-6150 5425)(-6350 5425);
WIRE 16 -1 (-6150 5475)(-6350 5475);
WIRE 16 -1 (-6150 5525)(-6350 5525);
WIRE 16 -1 (-7550 4475)(-8350 4475);
FORCEPROP 2 LAST SIG_NAME M_D_CPU1_SB_CS_N<1>
J 0
(-8300 4485);
DISPLAY 0.489362 (-8300 4485);
WIRE 16 -1 (-7550 4625)(-8350 4625);
FORCEPROP 2 LAST SIG_NAME M_D_CPU1_SA_CS_N<1>
J 0
(-8300 4635);
DISPLAY 0.489362 (-8300 4635);
WIRE 16 -1 (-7550 4425)(-8350 4425);
FORCEPROP 2 LAST SIG_NAME M_D_CPU1_SB_CS_N<0>
J 0
(-8300 4435);
DISPLAY 0.489362 (-8300 4435);
WIRE 16 -1 (-7550 4575)(-8350 4575);
FORCEPROP 2 LAST SIG_NAME M_D_CPU1_SA_CS_N<0>
J 0
(-8300 4585);
DISPLAY 0.489362 (-8300 4585);
WIRE 16 -1 (-7550 4325)(-8350 4325);
FORCEPROP 2 LAST SIG_NAME M_D_CPU1_CLK_DP<0>
J 0
(-8300 4335);
DISPLAY 0.489362 (-8300 4335);
WIRE 16 -1 (-7550 4275)(-8350 4275);
FORCEPROP 2 LAST SIG_NAME M_D_CPU1_CLK_DN<0>
J 0
(-8300 4285);
DISPLAY 0.489362 (-8300 4285);
WIRE 16 -1 (-7550 3475)(-7750 3475);
WIRE 16 -1 (-7550 3525)(-7750 3525);
WIRE 16 -1 (-7550 3575)(-7750 3575);
WIRE 16 -1 (-7550 3625)(-7750 3625);
WIRE 16 -1 (-7550 3675)(-7750 3675);
WIRE 16 -1 (-7550 3825)(-7750 3825);
WIRE 16 -1 (-7550 3925)(-7750 3925);
WIRE 16 -1 (-7550 3975)(-7750 3975);
WIRE 16 -1 (-7550 4075)(-7750 4075);
WIRE 16 -1 (-7550 4125)(-7750 4125);
WIRE 16 -1 (-7550 5175)(-7750 5175);
WIRE 16 -1 (-7550 5575)(-7750 5575);
WIRE 16 -1 (-7550 5125)(-7750 5125);
WIRE 16 -1 (-7550 5525)(-7750 5525);
WIRE 16 -1 (-7550 5075)(-7750 5075);
WIRE 16 -1 (-7550 5475)(-7750 5475);
WIRE 16 -1 (-7550 5025)(-7750 5025);
WIRE 16 -1 (-7550 5425)(-7750 5425);
WIRE 16 -1 (-7550 4975)(-7750 4975);
WIRE 16 -1 (-7550 5375)(-7750 5375);
WIRE 16 -1 (-7550 4925)(-7750 4925);
WIRE 16 -1 (-7550 5325)(-7750 5325);
WIRE 16 -1 (-7550 4875)(-7750 4875);
WIRE 16 -1 (-7550 5275)(-7750 5275);
WIRE 16 -1 (-7550 3725)(-7750 3725);
WIRE 16 -1 (-7550 3875)(-7750 3875);
WIRE 16 -1 (-7550 4025)(-7750 4025);
WIRE 16 -1 (-7550 4175)(-7750 4175);
WIRE 16 -1 (-6525 1600)(-6525 1525);
WIRE 16 -1 (-6525 1600)(-7250 1600);
FORCEPROP 2 LAST SIG_NAME PD_CHD_CPU1_DIMM_SAA
J 0
(-7235 1610);
DISPLAY 0.489362 (-7235 1610);
DOT 1 (-8475 2325);
DOT 1 (-2200 5100);
DOT 1 (-400 5350);
DOT 1 (-400 5250);
DOT 1 (-400 5300);
DOT 1 (-400 5200);
DOT 1 (-400 5150);
DOT 1 (-400 5100);
DOT 1 (-400 5050);
DOT 1 (-400 5000);
DOT 1 (-400 4950);
DOT 1 (-400 4850);
DOT 1 (-400 4900);
DOT 1 (-400 4800);
DOT 1 (-400 4750);
DOT 1 (-400 4700);
DOT 1 (-400 4600);
DOT 1 (-400 4650);
DOT 1 (-400 4550);
DOT 1 (-400 4450);
DOT 1 (-400 4500);
DOT 1 (-400 4350);
DOT 1 (-400 4400);
DOT 1 (-400 4300);
DOT 1 (-400 4250);
DOT 1 (-400 4200);
DOT 1 (-400 4150);
DOT 1 (-400 4100);
DOT 1 (-400 4050);
DOT 1 (-400 4000);
DOT 1 (-400 3950);
DOT 1 (-400 3900);
DOT 1 (-400 3850);
DOT 1 (-2200 5400);
DOT 1 (-2200 5350);
DOT 1 (-2200 5200);
DOT 1 (-2200 5150);
DOT 1 (-2200 5050);
DOT 1 (-2200 5000);
DOT 1 (-2200 4950);
DOT 1 (-2200 4850);
DOT 1 (-2200 4900);
DOT 1 (-2200 4800);
DOT 1 (-2200 4750);
DOT 1 (-2200 4700);
DOT 1 (-2200 4600);
DOT 1 (-2200 4650);
DOT 1 (-2200 4550);
DOT 1 (-2200 4450);
DOT 1 (-2200 4500);
DOT 1 (-2200 4350);
DOT 1 (-2200 4400);
DOT 1 (-2200 4300);
DOT 1 (-2200 4250);
DOT 1 (-2200 4200);
DOT 1 (-2200 4100);
DOT 1 (-2200 4150);
DOT 1 (-2200 4050);
DOT 1 (-2200 4000);
DOT 1 (-2200 3950);
DOT 1 (-2200 3900);
DOT 1 (-2200 3850);
DOT 1 (-2200 3800);
DOT 1 (-400 3800);
DOT 1 (-400 3700);
DOT 1 (-400 3750);
DOT 1 (-400 3650);
DOT 1 (-400 3600);
DOT 1 (-400 3550);
DOT 1 (-400 3450);
DOT 1 (-400 3500);
DOT 1 (-400 3400);
DOT 1 (-400 3350);
DOT 1 (-400 3300);
DOT 1 (-400 3250);
DOT 1 (-400 3200);
DOT 1 (-400 3150);
DOT 1 (-400 3100);
DOT 1 (-400 3050);
DOT 1 (-400 3000);
DOT 1 (-400 2950);
DOT 1 (-400 2850);
DOT 1 (-400 2900);
DOT 1 (-400 2800);
DOT 1 (-400 2750);
DOT 1 (-400 2700);
DOT 1 (-400 2650);
DOT 1 (-400 2550);
DOT 1 (-400 2600);
DOT 1 (-400 2500);
DOT 1 (-400 2450);
DOT 1 (-400 2400);
DOT 1 (-400 2300);
DOT 1 (-400 2350);
DOT 1 (-400 2150);
DOT 1 (-400 2250);
DOT 1 (-400 2100);
DOT 1 (-400 2050);
DOT 1 (-2200 3700);
DOT 1 (-2200 3750);
DOT 1 (-2200 3650);
DOT 1 (-2200 3600);
DOT 1 (-2200 3550);
DOT 1 (-2200 3450);
DOT 1 (-2200 3500);
DOT 1 (-2200 3400);
DOT 1 (-2200 3350);
DOT 1 (-2200 3300);
DOT 1 (-2200 3250);
DOT 1 (-2200 3200);
DOT 1 (-2200 3150);
DOT 1 (-2200 3100);
DOT 1 (-2200 3050);
DOT 1 (-2200 2950);
DOT 1 (-2200 3000);
DOT 1 (-2200 2800);
DOT 1 (-2200 2850);
DOT 1 (-2200 2900);
DOT 1 (-2200 2750);
DOT 1 (-2200 2700);
DOT 1 (-2200 2650);
DOT 1 (-2200 2550);
DOT 1 (-2200 2600);
DOT 1 (-2200 2500);
DOT 1 (-2200 2450);
DOT 1 (-2200 2400);
DOT 1 (-2200 2300);
DOT 1 (-2200 2350);
DOT 1 (-2200 2250);
DOT 1 (-2200 2200);
DOT 1 (-2200 2150);
DOT 1 (-8650 3525);
DOT 1 (-2900 5575);
DOT 1 (-2900 6000);
DOT 1 (-2325 6000);
QUIT
